%FSTAX25Y25*%
%MOIN*%
%SFA1B1*%

%IPPOS*%
%ADD10C,0.009840*%
%ADD11C,0.007870*%
%ADD12C,0.003940*%
%ADD13C,0.010000*%
%ADD14C,0.015750*%
%ADD15C,0.015750*%
%ADD16C,0.004720*%
%ADD17C,0.006000*%
%ADD18C,0.005000*%
%ADD19C,0.005910*%
%ADD20C,0.007000*%
%ADD21C,0.009000*%
%LNtimecard-dc-beta-v1-1*%
%LPD*%
G54D10*
X0100098Y0152362D02*
D01*
X0100096Y0152396*
X0100093Y015243*
X0100087Y0152464*
X0100078Y0152497*
X0100068Y015253*
X0100055Y0152562*
X010004Y0152592*
X0100023Y0152622*
X0100004Y0152651*
X0099982Y0152678*
X0099959Y0152703*
X0099935Y0152727*
X0099908Y0152749*
X0099881Y0152769*
X0099852Y0152788*
X0099821Y0152804*
X009979Y0152818*
X0099758Y0152829*
X0099725Y0152839*
X0099691Y0152846*
X0099657Y0152851*
X0099623Y0152853*
X0099588*
X0099554Y0152851*
X009952Y0152846*
X0099486Y0152839*
X0099453Y0152829*
X0099421Y0152818*
X009939Y0152804*
X009936Y0152788*
X009933Y0152769*
X0099303Y0152749*
X0099276Y0152727*
X0099252Y0152703*
X0099229Y0152678*
X0099207Y0152651*
X0099188Y0152622*
X0099171Y0152592*
X0099156Y0152562*
X0099143Y015253*
X0099133Y0152497*
X0099124Y0152464*
X0099118Y015243*
X0099115Y0152396*
X0099114Y0152362*
X0099115Y0152327*
X0099118Y0152293*
X0099124Y0152259*
X0099133Y0152226*
X0099143Y0152193*
X0099156Y0152161*
X0099171Y0152131*
X0099188Y0152101*
X0099207Y0152072*
X0099229Y0152045*
X0099252Y015202*
X0099276Y0151996*
X0099303Y0151974*
X009933Y0151954*
X009936Y0151935*
X009939Y0151919*
X0099421Y0151905*
X0099453Y0151894*
X0099486Y0151884*
X009952Y0151877*
X0099554Y0151872*
X0099588Y015187*
X0099623*
X0099657Y0151872*
X0099691Y0151877*
X0099725Y0151884*
X0099758Y0151894*
X009979Y0151905*
X0099821Y0151919*
X0099852Y0151935*
X0099881Y0151954*
X0099908Y0151974*
X0099935Y0151996*
X0099959Y015202*
X0099982Y0152045*
X0100004Y0152072*
X0100023Y0152101*
X010004Y0152131*
X0100055Y0152161*
X0100068Y0152193*
X0100078Y0152226*
X0100087Y0152259*
X0100093Y0152293*
X0100096Y0152327*
X0100098Y0152362*
X0059547Y0083551D02*
D01*
X0059545Y0083585*
X0059542Y0083619*
X0059536Y0083653*
X0059527Y0083686*
X0059517Y0083719*
X0059504Y0083751*
X0059489Y0083781*
X0059472Y0083811*
X0059453Y008384*
X0059431Y0083867*
X0059408Y0083892*
X0059384Y0083916*
X0059357Y0083938*
X005933Y0083958*
X0059301Y0083977*
X005927Y0083993*
X0059239Y0084007*
X0059207Y0084018*
X0059174Y0084028*
X005914Y0084035*
X0059106Y008404*
X0059072Y0084042*
X0059037*
X0059003Y008404*
X0058969Y0084035*
X0058935Y0084028*
X0058902Y0084018*
X005887Y0084007*
X0058839Y0083993*
X0058809Y0083977*
X0058779Y0083958*
X0058752Y0083938*
X0058725Y0083916*
X0058701Y0083892*
X0058678Y0083867*
X0058656Y008384*
X0058637Y0083811*
X005862Y0083781*
X0058605Y0083751*
X0058592Y0083719*
X0058582Y0083686*
X0058573Y0083653*
X0058567Y0083619*
X0058564Y0083585*
X0058563Y0083551*
X0058564Y0083516*
X0058567Y0083482*
X0058573Y0083448*
X0058582Y0083415*
X0058592Y0083382*
X0058605Y008335*
X005862Y008332*
X0058637Y008329*
X0058656Y0083261*
X0058678Y0083234*
X0058701Y0083209*
X0058725Y0083185*
X0058752Y0083163*
X0058779Y0083143*
X0058809Y0083124*
X0058839Y0083108*
X005887Y0083094*
X0058902Y0083083*
X0058935Y0083073*
X0058969Y0083066*
X0059003Y0083061*
X0059037Y0083059*
X0059072*
X0059106Y0083061*
X005914Y0083066*
X0059174Y0083073*
X0059207Y0083083*
X0059239Y0083094*
X005927Y0083108*
X0059301Y0083124*
X005933Y0083143*
X0059357Y0083163*
X0059384Y0083185*
X0059408Y0083209*
X0059431Y0083234*
X0059453Y0083261*
X0059472Y008329*
X0059489Y008332*
X0059504Y008335*
X0059517Y0083382*
X0059527Y0083415*
X0059536Y0083448*
X0059542Y0083482*
X0059545Y0083516*
X0059547Y0083551*
X0214075Y0354528D02*
D01*
X0214073Y0354562*
X021407Y0354596*
X0214064Y035463*
X0214055Y0354663*
X0214045Y0354696*
X0214032Y0354728*
X0214017Y0354758*
X0214Y0354788*
X0213981Y0354817*
X0213959Y0354844*
X0213936Y0354869*
X0213912Y0354893*
X0213885Y0354915*
X0213858Y0354935*
X0213829Y0354954*
X0213798Y035497*
X0213767Y0354984*
X0213735Y0354995*
X0213702Y0355005*
X0213668Y0355012*
X0213634Y0355017*
X02136Y0355019*
X0213565*
X0213531Y0355017*
X0213497Y0355012*
X0213463Y0355005*
X021343Y0354995*
X0213398Y0354984*
X0213367Y035497*
X0213337Y0354954*
X0213307Y0354935*
X021328Y0354915*
X0213253Y0354893*
X0213229Y0354869*
X0213206Y0354844*
X0213184Y0354817*
X0213165Y0354788*
X0213148Y0354758*
X0213133Y0354728*
X021312Y0354696*
X021311Y0354663*
X0213101Y035463*
X0213095Y0354596*
X0213092Y0354562*
X0213091Y0354528*
X0213092Y0354493*
X0213095Y0354459*
X0213101Y0354425*
X021311Y0354392*
X021312Y0354359*
X0213133Y0354327*
X0213148Y0354297*
X0213165Y0354267*
X0213184Y0354238*
X0213206Y0354211*
X0213229Y0354186*
X0213253Y0354162*
X021328Y035414*
X0213307Y035412*
X0213337Y0354101*
X0213367Y0354085*
X0213398Y0354071*
X021343Y035406*
X0213463Y035405*
X0213497Y0354043*
X0213531Y0354038*
X0213565Y0354036*
X02136*
X0213634Y0354038*
X0213668Y0354043*
X0213702Y035405*
X0213735Y035406*
X0213767Y0354071*
X0213798Y0354085*
X0213829Y0354101*
X0213858Y035412*
X0213885Y035414*
X0213912Y0354162*
X0213936Y0354186*
X0213959Y0354211*
X0213981Y0354238*
X0214Y0354267*
X0214017Y0354297*
X0214032Y0354327*
X0214045Y0354359*
X0214055Y0354392*
X0214064Y0354425*
X021407Y0354459*
X0214073Y0354493*
X0214075Y0354528*
X0535925Y0293779D02*
D01*
X0535923Y0293813*
X053592Y0293847*
X0535914Y0293881*
X0535905Y0293914*
X0535895Y0293947*
X0535882Y0293979*
X0535867Y0294009*
X053585Y0294039*
X0535831Y0294068*
X0535809Y0294095*
X0535786Y029412*
X0535762Y0294144*
X0535735Y0294166*
X0535708Y0294186*
X0535679Y0294205*
X0535648Y0294221*
X0535617Y0294235*
X0535585Y0294246*
X0535552Y0294256*
X0535518Y0294263*
X0535484Y0294268*
X053545Y029427*
X0535415*
X0535381Y0294268*
X0535347Y0294263*
X0535313Y0294256*
X053528Y0294246*
X0535248Y0294235*
X0535217Y0294221*
X0535187Y0294205*
X0535157Y0294186*
X053513Y0294166*
X0535103Y0294144*
X0535079Y029412*
X0535056Y0294095*
X0535034Y0294068*
X0535015Y0294039*
X0534998Y0294009*
X0534983Y0293979*
X053497Y0293947*
X053496Y0293914*
X0534951Y0293881*
X0534945Y0293847*
X0534942Y0293813*
X0534941Y0293779*
X0534942Y0293744*
X0534945Y029371*
X0534951Y0293676*
X053496Y0293643*
X053497Y029361*
X0534983Y0293578*
X0534998Y0293548*
X0535015Y0293518*
X0535034Y0293489*
X0535056Y0293462*
X0535079Y0293437*
X0535103Y0293413*
X053513Y0293391*
X0535157Y0293371*
X0535187Y0293352*
X0535217Y0293336*
X0535248Y0293322*
X053528Y0293311*
X0535313Y0293301*
X0535347Y0293294*
X0535381Y0293289*
X0535415Y0293287*
X053545*
X0535484Y0293289*
X0535518Y0293294*
X0535552Y0293301*
X0535585Y0293311*
X0535617Y0293322*
X0535648Y0293336*
X0535679Y0293352*
X0535708Y0293371*
X0535735Y0293391*
X0535762Y0293413*
X0535786Y0293437*
X0535809Y0293462*
X0535831Y0293489*
X053585Y0293518*
X0535867Y0293548*
X0535882Y0293578*
X0535895Y029361*
X0535905Y0293643*
X0535914Y0293676*
X053592Y029371*
X0535923Y0293744*
X0535925Y0293779*
X046565Y0293327D02*
D01*
X0465648Y0293361*
X0465645Y0293395*
X0465639Y0293429*
X046563Y0293462*
X046562Y0293495*
X0465607Y0293527*
X0465592Y0293557*
X0465575Y0293587*
X0465556Y0293616*
X0465534Y0293643*
X0465511Y0293668*
X0465487Y0293692*
X046546Y0293714*
X0465433Y0293734*
X0465404Y0293753*
X0465373Y0293769*
X0465342Y0293783*
X046531Y0293794*
X0465277Y0293804*
X0465243Y0293811*
X0465209Y0293816*
X0465175Y0293818*
X046514*
X0465106Y0293816*
X0465072Y0293811*
X0465038Y0293804*
X0465005Y0293794*
X0464973Y0293783*
X0464942Y0293769*
X0464912Y0293753*
X0464882Y0293734*
X0464855Y0293714*
X0464828Y0293692*
X0464804Y0293668*
X0464781Y0293643*
X0464759Y0293616*
X046474Y0293587*
X0464723Y0293557*
X0464708Y0293527*
X0464695Y0293495*
X0464685Y0293462*
X0464676Y0293429*
X046467Y0293395*
X0464667Y0293361*
X0464666Y0293327*
X0464667Y0293292*
X046467Y0293258*
X0464676Y0293224*
X0464685Y0293191*
X0464695Y0293158*
X0464708Y0293126*
X0464723Y0293096*
X046474Y0293066*
X0464759Y0293037*
X0464781Y029301*
X0464804Y0292985*
X0464828Y0292961*
X0464855Y0292939*
X0464882Y0292919*
X0464912Y02929*
X0464942Y0292884*
X0464973Y029287*
X0465005Y0292859*
X0465038Y0292849*
X0465072Y0292842*
X0465106Y0292837*
X046514Y0292835*
X0465175*
X0465209Y0292837*
X0465243Y0292842*
X0465277Y0292849*
X046531Y0292859*
X0465342Y029287*
X0465373Y0292884*
X0465404Y02929*
X0465433Y0292919*
X046546Y0292939*
X0465487Y0292961*
X0465511Y0292985*
X0465534Y029301*
X0465556Y0293037*
X0465575Y0293066*
X0465592Y0293096*
X0465607Y0293126*
X046562Y0293158*
X046563Y0293191*
X0465639Y0293224*
X0465645Y0293258*
X0465648Y0293292*
X046565Y0293327*
X0314567Y0285433D02*
D01*
X0314565Y0285467*
X0314562Y0285501*
X0314556Y0285535*
X0314547Y0285568*
X0314537Y0285601*
X0314524Y0285633*
X0314509Y0285663*
X0314492Y0285693*
X0314473Y0285722*
X0314451Y0285749*
X0314428Y0285774*
X0314404Y0285798*
X0314377Y028582*
X031435Y028584*
X0314321Y0285859*
X031429Y0285875*
X0314259Y0285889*
X0314227Y02859*
X0314194Y028591*
X031416Y0285917*
X0314126Y0285922*
X0314092Y0285924*
X0314057*
X0314023Y0285922*
X0313989Y0285917*
X0313955Y028591*
X0313922Y02859*
X031389Y0285889*
X0313859Y0285875*
X0313829Y0285859*
X0313799Y028584*
X0313772Y028582*
X0313745Y0285798*
X0313721Y0285774*
X0313698Y0285749*
X0313676Y0285722*
X0313657Y0285693*
X031364Y0285663*
X0313625Y0285633*
X0313612Y0285601*
X0313602Y0285568*
X0313593Y0285535*
X0313587Y0285501*
X0313584Y0285467*
X0313583Y0285433*
X0313584Y0285398*
X0313587Y0285364*
X0313593Y028533*
X0313602Y0285297*
X0313612Y0285264*
X0313625Y0285232*
X031364Y0285202*
X0313657Y0285172*
X0313676Y0285143*
X0313698Y0285116*
X0313721Y0285091*
X0313745Y0285067*
X0313772Y0285045*
X0313799Y0285025*
X0313829Y0285006*
X0313859Y028499*
X031389Y0284976*
X0313922Y0284965*
X0313955Y0284955*
X0313989Y0284948*
X0314023Y0284943*
X0314057Y0284941*
X0314092*
X0314126Y0284943*
X031416Y0284948*
X0314194Y0284955*
X0314227Y0284965*
X0314259Y0284976*
X031429Y028499*
X0314321Y0285006*
X031435Y0285025*
X0314377Y0285045*
X0314404Y0285067*
X0314428Y0285091*
X0314451Y0285116*
X0314473Y0285143*
X0314492Y0285172*
X0314509Y0285202*
X0314524Y0285232*
X0314537Y0285264*
X0314547Y0285297*
X0314556Y028533*
X0314562Y0285364*
X0314565Y0285398*
X0314567Y0285433*
X0361122Y0286319D02*
D01*
X036112Y0286353*
X0361117Y0286387*
X0361111Y0286421*
X0361102Y0286454*
X0361092Y0286487*
X0361079Y0286519*
X0361064Y0286549*
X0361047Y0286579*
X0361028Y0286608*
X0361006Y0286635*
X0360983Y028666*
X0360959Y0286684*
X0360932Y0286706*
X0360905Y0286726*
X0360876Y0286745*
X0360845Y0286761*
X0360814Y0286775*
X0360782Y0286786*
X0360749Y0286796*
X0360715Y0286803*
X0360681Y0286808*
X0360647Y028681*
X0360612*
X0360578Y0286808*
X0360544Y0286803*
X036051Y0286796*
X0360477Y0286786*
X0360445Y0286775*
X0360414Y0286761*
X0360384Y0286745*
X0360354Y0286726*
X0360327Y0286706*
X03603Y0286684*
X0360276Y028666*
X0360253Y0286635*
X0360231Y0286608*
X0360212Y0286579*
X0360195Y0286549*
X036018Y0286519*
X0360167Y0286487*
X0360157Y0286454*
X0360148Y0286421*
X0360142Y0286387*
X0360139Y0286353*
X0360138Y0286319*
X0360139Y0286284*
X0360142Y028625*
X0360148Y0286216*
X0360157Y0286183*
X0360167Y028615*
X036018Y0286118*
X0360195Y0286088*
X0360212Y0286058*
X0360231Y0286029*
X0360253Y0286002*
X0360276Y0285977*
X03603Y0285953*
X0360327Y0285931*
X0360354Y0285911*
X0360384Y0285892*
X0360414Y0285876*
X0360445Y0285862*
X0360477Y0285851*
X036051Y0285841*
X0360544Y0285834*
X0360578Y0285829*
X0360612Y0285827*
X0360647*
X0360681Y0285829*
X0360715Y0285834*
X0360749Y0285841*
X0360782Y0285851*
X0360814Y0285862*
X0360845Y0285876*
X0360876Y0285892*
X0360905Y0285911*
X0360932Y0285931*
X0360959Y0285953*
X0360983Y0285977*
X0361006Y0286002*
X0361028Y0286029*
X0361047Y0286058*
X0361064Y0286088*
X0361079Y0286118*
X0361092Y028615*
X0361102Y0286183*
X0361111Y0286216*
X0361117Y028625*
X036112Y0286284*
X0361122Y0286319*
X0302461Y0290198D02*
D01*
X0302459Y0290232*
X0302456Y0290266*
X030245Y02903*
X0302441Y0290333*
X0302431Y0290366*
X0302418Y0290398*
X0302403Y0290428*
X0302386Y0290458*
X0302367Y0290487*
X0302345Y0290514*
X0302322Y0290539*
X0302298Y0290563*
X0302271Y0290585*
X0302244Y0290605*
X0302215Y0290624*
X0302184Y029064*
X0302153Y0290654*
X0302121Y0290665*
X0302088Y0290675*
X0302054Y0290682*
X030202Y0290687*
X0301986Y0290689*
X0301951*
X0301917Y0290687*
X0301883Y0290682*
X0301849Y0290675*
X0301816Y0290665*
X0301784Y0290654*
X0301753Y029064*
X0301723Y0290624*
X0301693Y0290605*
X0301666Y0290585*
X0301639Y0290563*
X0301615Y0290539*
X0301592Y0290514*
X030157Y0290487*
X0301551Y0290458*
X0301534Y0290428*
X0301519Y0290398*
X0301506Y0290366*
X0301496Y0290333*
X0301487Y02903*
X0301481Y0290266*
X0301478Y0290232*
X0301477Y0290198*
X0301478Y0290163*
X0301481Y0290129*
X0301487Y0290095*
X0301496Y0290062*
X0301506Y0290029*
X0301519Y0289997*
X0301534Y0289967*
X0301551Y0289937*
X030157Y0289908*
X0301592Y0289881*
X0301615Y0289856*
X0301639Y0289832*
X0301666Y028981*
X0301693Y028979*
X0301723Y0289771*
X0301753Y0289755*
X0301784Y0289741*
X0301816Y028973*
X0301849Y028972*
X0301883Y0289713*
X0301917Y0289708*
X0301951Y0289706*
X0301986*
X030202Y0289708*
X0302054Y0289713*
X0302088Y028972*
X0302121Y028973*
X0302153Y0289741*
X0302184Y0289755*
X0302215Y0289771*
X0302244Y028979*
X0302271Y028981*
X0302298Y0289832*
X0302322Y0289856*
X0302345Y0289881*
X0302367Y0289908*
X0302386Y0289937*
X0302403Y0289967*
X0302418Y0289997*
X0302431Y0290029*
X0302441Y0290062*
X030245Y0290095*
X0302456Y0290129*
X0302459Y0290163*
X0302461Y0290198*
X0099902Y0100394D02*
D01*
X00999Y0100428*
X0099897Y0100462*
X0099891Y0100496*
X0099882Y0100529*
X0099872Y0100562*
X0099859Y0100594*
X0099844Y0100624*
X0099827Y0100654*
X0099808Y0100683*
X0099786Y010071*
X0099763Y0100735*
X0099739Y0100759*
X0099712Y0100781*
X0099685Y0100801*
X0099656Y010082*
X0099625Y0100836*
X0099594Y010085*
X0099562Y0100861*
X0099529Y0100871*
X0099495Y0100878*
X0099461Y0100883*
X0099427Y0100885*
X0099392*
X0099358Y0100883*
X0099324Y0100878*
X009929Y0100871*
X0099257Y0100861*
X0099225Y010085*
X0099194Y0100836*
X0099164Y010082*
X0099134Y0100801*
X0099107Y0100781*
X009908Y0100759*
X0099056Y0100735*
X0099033Y010071*
X0099011Y0100683*
X0098992Y0100654*
X0098975Y0100624*
X009896Y0100594*
X0098947Y0100562*
X0098937Y0100529*
X0098928Y0100496*
X0098922Y0100462*
X0098919Y0100428*
X0098918Y0100394*
X0098919Y0100359*
X0098922Y0100325*
X0098928Y0100291*
X0098937Y0100258*
X0098947Y0100225*
X009896Y0100193*
X0098975Y0100163*
X0098992Y0100133*
X0099011Y0100104*
X0099033Y0100077*
X0099056Y0100052*
X009908Y0100028*
X0099107Y0100006*
X0099134Y0099986*
X0099164Y0099967*
X0099194Y0099951*
X0099225Y0099937*
X0099257Y0099926*
X009929Y0099916*
X0099324Y0099909*
X0099358Y0099904*
X0099392Y0099902*
X0099427*
X0099461Y0099904*
X0099495Y0099909*
X0099529Y0099916*
X0099562Y0099926*
X0099594Y0099937*
X0099625Y0099951*
X0099656Y0099967*
X0099685Y0099986*
X0099712Y0100006*
X0099739Y0100028*
X0099763Y0100052*
X0099786Y0100077*
X0099808Y0100104*
X0099827Y0100133*
X0099844Y0100163*
X0099859Y0100193*
X0099872Y0100225*
X0099882Y0100258*
X0099891Y0100291*
X0099897Y0100325*
X00999Y0100359*
X0099902Y0100394*
X0160433Y0354528D02*
D01*
X0160431Y0354562*
X0160428Y0354596*
X0160422Y035463*
X0160413Y0354663*
X0160403Y0354696*
X016039Y0354728*
X0160375Y0354758*
X0160358Y0354788*
X0160339Y0354817*
X0160317Y0354844*
X0160294Y0354869*
X016027Y0354893*
X0160243Y0354915*
X0160216Y0354935*
X0160187Y0354954*
X0160156Y035497*
X0160125Y0354984*
X0160093Y0354995*
X016006Y0355005*
X0160026Y0355012*
X0159992Y0355017*
X0159958Y0355019*
X0159923*
X0159889Y0355017*
X0159855Y0355012*
X0159821Y0355005*
X0159788Y0354995*
X0159756Y0354984*
X0159725Y035497*
X0159695Y0354954*
X0159665Y0354935*
X0159638Y0354915*
X0159611Y0354893*
X0159587Y0354869*
X0159564Y0354844*
X0159542Y0354817*
X0159523Y0354788*
X0159506Y0354758*
X0159491Y0354728*
X0159478Y0354696*
X0159468Y0354663*
X0159459Y035463*
X0159453Y0354596*
X015945Y0354562*
X0159449Y0354528*
X015945Y0354493*
X0159453Y0354459*
X0159459Y0354425*
X0159468Y0354392*
X0159478Y0354359*
X0159491Y0354327*
X0159506Y0354297*
X0159523Y0354267*
X0159542Y0354238*
X0159564Y0354211*
X0159587Y0354186*
X0159611Y0354162*
X0159638Y035414*
X0159665Y035412*
X0159695Y0354101*
X0159725Y0354085*
X0159756Y0354071*
X0159788Y035406*
X0159821Y035405*
X0159855Y0354043*
X0159889Y0354038*
X0159923Y0354036*
X0159958*
X0159992Y0354038*
X0160026Y0354043*
X016006Y035405*
X0160093Y035406*
X0160125Y0354071*
X0160156Y0354085*
X0160187Y0354101*
X0160216Y035412*
X0160243Y035414*
X016027Y0354162*
X0160294Y0354186*
X0160317Y0354211*
X0160339Y0354238*
X0160358Y0354267*
X0160375Y0354297*
X016039Y0354327*
X0160403Y0354359*
X0160413Y0354392*
X0160422Y0354425*
X0160428Y0354459*
X0160431Y0354493*
X0160433Y0354528*
X017815D02*
D01*
X0178148Y0354562*
X0178145Y0354596*
X0178139Y035463*
X017813Y0354663*
X017812Y0354696*
X0178107Y0354728*
X0178092Y0354758*
X0178075Y0354788*
X0178056Y0354817*
X0178034Y0354844*
X0178011Y0354869*
X0177987Y0354893*
X017796Y0354915*
X0177933Y0354935*
X0177904Y0354954*
X0177873Y035497*
X0177842Y0354984*
X017781Y0354995*
X0177777Y0355005*
X0177743Y0355012*
X0177709Y0355017*
X0177675Y0355019*
X017764*
X0177606Y0355017*
X0177572Y0355012*
X0177538Y0355005*
X0177505Y0354995*
X0177473Y0354984*
X0177442Y035497*
X0177412Y0354954*
X0177382Y0354935*
X0177355Y0354915*
X0177328Y0354893*
X0177304Y0354869*
X0177281Y0354844*
X0177259Y0354817*
X017724Y0354788*
X0177223Y0354758*
X0177208Y0354728*
X0177195Y0354696*
X0177185Y0354663*
X0177176Y035463*
X017717Y0354596*
X0177167Y0354562*
X0177166Y0354528*
X0177167Y0354493*
X017717Y0354459*
X0177176Y0354425*
X0177185Y0354392*
X0177195Y0354359*
X0177208Y0354327*
X0177223Y0354297*
X017724Y0354267*
X0177259Y0354238*
X0177281Y0354211*
X0177304Y0354186*
X0177328Y0354162*
X0177355Y035414*
X0177382Y035412*
X0177412Y0354101*
X0177442Y0354085*
X0177473Y0354071*
X0177505Y035406*
X0177538Y035405*
X0177572Y0354043*
X0177606Y0354038*
X017764Y0354036*
X0177675*
X0177709Y0354038*
X0177743Y0354043*
X0177777Y035405*
X017781Y035406*
X0177842Y0354071*
X0177873Y0354085*
X0177904Y0354101*
X0177933Y035412*
X017796Y035414*
X0177987Y0354162*
X0178011Y0354186*
X0178034Y0354211*
X0178056Y0354238*
X0178075Y0354267*
X0178092Y0354297*
X0178107Y0354327*
X017812Y0354359*
X017813Y0354392*
X0178139Y0354425*
X0178145Y0354459*
X0178148Y0354493*
X017815Y0354528*
X0196358D02*
D01*
X0196356Y0354562*
X0196353Y0354596*
X0196347Y035463*
X0196338Y0354663*
X0196328Y0354696*
X0196315Y0354728*
X01963Y0354758*
X0196283Y0354788*
X0196264Y0354817*
X0196242Y0354844*
X0196219Y0354869*
X0196195Y0354893*
X0196168Y0354915*
X0196141Y0354935*
X0196112Y0354954*
X0196081Y035497*
X019605Y0354984*
X0196018Y0354995*
X0195985Y0355005*
X0195951Y0355012*
X0195917Y0355017*
X0195883Y0355019*
X0195848*
X0195814Y0355017*
X019578Y0355012*
X0195746Y0355005*
X0195713Y0354995*
X0195681Y0354984*
X019565Y035497*
X019562Y0354954*
X019559Y0354935*
X0195563Y0354915*
X0195536Y0354893*
X0195512Y0354869*
X0195489Y0354844*
X0195467Y0354817*
X0195448Y0354788*
X0195431Y0354758*
X0195416Y0354728*
X0195403Y0354696*
X0195393Y0354663*
X0195384Y035463*
X0195378Y0354596*
X0195375Y0354562*
X0195374Y0354528*
X0195375Y0354493*
X0195378Y0354459*
X0195384Y0354425*
X0195393Y0354392*
X0195403Y0354359*
X0195416Y0354327*
X0195431Y0354297*
X0195448Y0354267*
X0195467Y0354238*
X0195489Y0354211*
X0195512Y0354186*
X0195536Y0354162*
X0195563Y035414*
X019559Y035412*
X019562Y0354101*
X019565Y0354085*
X0195681Y0354071*
X0195713Y035406*
X0195746Y035405*
X019578Y0354043*
X0195814Y0354038*
X0195848Y0354036*
X0195883*
X0195917Y0354038*
X0195951Y0354043*
X0195985Y035405*
X0196018Y035406*
X019605Y0354071*
X0196081Y0354085*
X0196112Y0354101*
X0196141Y035412*
X0196168Y035414*
X0196195Y0354162*
X0196219Y0354186*
X0196242Y0354211*
X0196264Y0354238*
X0196283Y0354267*
X01963Y0354297*
X0196315Y0354327*
X0196328Y0354359*
X0196338Y0354392*
X0196347Y0354425*
X0196353Y0354459*
X0196356Y0354493*
X0196358Y0354528*
X0059547Y0188276D02*
D01*
X0059545Y018831*
X0059542Y0188344*
X0059536Y0188378*
X0059527Y0188411*
X0059517Y0188444*
X0059504Y0188476*
X0059489Y0188506*
X0059472Y0188536*
X0059453Y0188565*
X0059431Y0188592*
X0059408Y0188617*
X0059384Y0188641*
X0059357Y0188663*
X005933Y0188683*
X0059301Y0188702*
X005927Y0188718*
X0059239Y0188732*
X0059207Y0188743*
X0059174Y0188753*
X005914Y018876*
X0059106Y0188765*
X0059072Y0188767*
X0059037*
X0059003Y0188765*
X0058969Y018876*
X0058935Y0188753*
X0058902Y0188743*
X005887Y0188732*
X0058839Y0188718*
X0058809Y0188702*
X0058779Y0188683*
X0058752Y0188663*
X0058725Y0188641*
X0058701Y0188617*
X0058678Y0188592*
X0058656Y0188565*
X0058637Y0188536*
X005862Y0188506*
X0058605Y0188476*
X0058592Y0188444*
X0058582Y0188411*
X0058573Y0188378*
X0058567Y0188344*
X0058564Y018831*
X0058563Y0188276*
X0058564Y0188241*
X0058567Y0188207*
X0058573Y0188173*
X0058582Y018814*
X0058592Y0188107*
X0058605Y0188075*
X005862Y0188045*
X0058637Y0188015*
X0058656Y0187986*
X0058678Y0187959*
X0058701Y0187934*
X0058725Y018791*
X0058752Y0187888*
X0058779Y0187868*
X0058809Y0187849*
X0058839Y0187833*
X005887Y0187819*
X0058902Y0187808*
X0058935Y0187798*
X0058969Y0187791*
X0059003Y0187786*
X0059037Y0187784*
X0059072*
X0059106Y0187786*
X005914Y0187791*
X0059174Y0187798*
X0059207Y0187808*
X0059239Y0187819*
X005927Y0187833*
X0059301Y0187849*
X005933Y0187868*
X0059357Y0187888*
X0059384Y018791*
X0059408Y0187934*
X0059431Y0187959*
X0059453Y0187986*
X0059472Y0188015*
X0059489Y0188045*
X0059504Y0188075*
X0059517Y0188107*
X0059527Y018814*
X0059536Y0188173*
X0059542Y0188207*
X0059545Y0188241*
X0059547Y0188276*
Y0241032D02*
D01*
X0059545Y0241066*
X0059542Y02411*
X0059536Y0241134*
X0059527Y0241167*
X0059517Y02412*
X0059504Y0241232*
X0059489Y0241262*
X0059472Y0241292*
X0059453Y0241321*
X0059431Y0241348*
X0059408Y0241373*
X0059384Y0241397*
X0059357Y0241419*
X005933Y0241439*
X0059301Y0241458*
X005927Y0241474*
X0059239Y0241488*
X0059207Y0241499*
X0059174Y0241509*
X005914Y0241516*
X0059106Y0241521*
X0059072Y0241523*
X0059037*
X0059003Y0241521*
X0058969Y0241516*
X0058935Y0241509*
X0058902Y0241499*
X005887Y0241488*
X0058839Y0241474*
X0058809Y0241458*
X0058779Y0241439*
X0058752Y0241419*
X0058725Y0241397*
X0058701Y0241373*
X0058678Y0241348*
X0058656Y0241321*
X0058637Y0241292*
X005862Y0241262*
X0058605Y0241232*
X0058592Y02412*
X0058582Y0241167*
X0058573Y0241134*
X0058567Y02411*
X0058564Y0241066*
X0058563Y0241032*
X0058564Y0240997*
X0058567Y0240963*
X0058573Y0240929*
X0058582Y0240896*
X0058592Y0240863*
X0058605Y0240831*
X005862Y0240801*
X0058637Y0240771*
X0058656Y0240742*
X0058678Y0240715*
X0058701Y024069*
X0058725Y0240666*
X0058752Y0240644*
X0058779Y0240624*
X0058809Y0240605*
X0058839Y0240589*
X005887Y0240575*
X0058902Y0240564*
X0058935Y0240554*
X0058969Y0240547*
X0059003Y0240542*
X0059037Y024054*
X0059072*
X0059106Y0240542*
X005914Y0240547*
X0059174Y0240554*
X0059207Y0240564*
X0059239Y0240575*
X005927Y0240589*
X0059301Y0240605*
X005933Y0240624*
X0059357Y0240644*
X0059384Y0240666*
X0059408Y024069*
X0059431Y0240715*
X0059453Y0240742*
X0059472Y0240771*
X0059489Y0240801*
X0059504Y0240831*
X0059517Y0240863*
X0059527Y0240896*
X0059536Y0240929*
X0059542Y0240963*
X0059545Y0240997*
X0059547Y0241032*
Y0136307D02*
D01*
X0059545Y0136341*
X0059542Y0136375*
X0059536Y0136409*
X0059527Y0136442*
X0059517Y0136475*
X0059504Y0136507*
X0059489Y0136537*
X0059472Y0136567*
X0059453Y0136596*
X0059431Y0136623*
X0059408Y0136648*
X0059384Y0136672*
X0059357Y0136694*
X005933Y0136714*
X0059301Y0136733*
X005927Y0136749*
X0059239Y0136763*
X0059207Y0136774*
X0059174Y0136784*
X005914Y0136791*
X0059106Y0136796*
X0059072Y0136798*
X0059037*
X0059003Y0136796*
X0058969Y0136791*
X0058935Y0136784*
X0058902Y0136774*
X005887Y0136763*
X0058839Y0136749*
X0058809Y0136733*
X0058779Y0136714*
X0058752Y0136694*
X0058725Y0136672*
X0058701Y0136648*
X0058678Y0136623*
X0058656Y0136596*
X0058637Y0136567*
X005862Y0136537*
X0058605Y0136507*
X0058592Y0136475*
X0058582Y0136442*
X0058573Y0136409*
X0058567Y0136375*
X0058564Y0136341*
X0058563Y0136307*
X0058564Y0136272*
X0058567Y0136238*
X0058573Y0136204*
X0058582Y0136171*
X0058592Y0136138*
X0058605Y0136106*
X005862Y0136076*
X0058637Y0136046*
X0058656Y0136017*
X0058678Y013599*
X0058701Y0135965*
X0058725Y0135941*
X0058752Y0135919*
X0058779Y0135899*
X0058809Y013588*
X0058839Y0135864*
X005887Y013585*
X0058902Y0135839*
X0058935Y0135829*
X0058969Y0135822*
X0059003Y0135817*
X0059037Y0135815*
X0059072*
X0059106Y0135817*
X005914Y0135822*
X0059174Y0135829*
X0059207Y0135839*
X0059239Y013585*
X005927Y0135864*
X0059301Y013588*
X005933Y0135899*
X0059357Y0135919*
X0059384Y0135941*
X0059408Y0135965*
X0059431Y013599*
X0059453Y0136017*
X0059472Y0136046*
X0059489Y0136076*
X0059504Y0136106*
X0059517Y0136138*
X0059527Y0136171*
X0059536Y0136204*
X0059542Y0136238*
X0059545Y0136272*
X0059547Y0136307*
X0120374Y024626D02*
D01*
X0120372Y0246294*
X0120369Y0246328*
X0120363Y0246362*
X0120354Y0246395*
X0120344Y0246428*
X0120331Y024646*
X0120316Y024649*
X0120299Y024652*
X012028Y0246549*
X0120258Y0246576*
X0120235Y0246601*
X0120211Y0246625*
X0120184Y0246647*
X0120157Y0246667*
X0120128Y0246686*
X0120097Y0246702*
X0120066Y0246716*
X0120034Y0246727*
X0120001Y0246737*
X0119967Y0246744*
X0119933Y0246749*
X0119899Y0246751*
X0119864*
X011983Y0246749*
X0119796Y0246744*
X0119762Y0246737*
X0119729Y0246727*
X0119697Y0246716*
X0119666Y0246702*
X0119636Y0246686*
X0119606Y0246667*
X0119579Y0246647*
X0119552Y0246625*
X0119528Y0246601*
X0119505Y0246576*
X0119483Y0246549*
X0119464Y024652*
X0119447Y024649*
X0119432Y024646*
X0119419Y0246428*
X0119409Y0246395*
X01194Y0246362*
X0119394Y0246328*
X0119391Y0246294*
X011939Y024626*
X0119391Y0246225*
X0119394Y0246191*
X01194Y0246157*
X0119409Y0246124*
X0119419Y0246091*
X0119432Y0246059*
X0119447Y0246029*
X0119464Y0245999*
X0119483Y024597*
X0119505Y0245943*
X0119528Y0245918*
X0119552Y0245894*
X0119579Y0245872*
X0119606Y0245852*
X0119636Y0245833*
X0119666Y0245817*
X0119697Y0245803*
X0119729Y0245792*
X0119762Y0245782*
X0119796Y0245775*
X011983Y024577*
X0119864Y0245768*
X0119899*
X0119933Y024577*
X0119967Y0245775*
X0120001Y0245782*
X0120034Y0245792*
X0120066Y0245803*
X0120097Y0245817*
X0120128Y0245833*
X0120157Y0245852*
X0120184Y0245872*
X0120211Y0245894*
X0120235Y0245918*
X0120258Y0245943*
X012028Y024597*
X0120299Y0245999*
X0120316Y0246029*
X0120331Y0246059*
X0120344Y0246091*
X0120354Y0246124*
X0120363Y0246157*
X0120369Y0246191*
X0120372Y0246225*
X0120374Y024626*
Y019311D02*
D01*
X0120372Y0193144*
X0120369Y0193178*
X0120363Y0193212*
X0120354Y0193245*
X0120344Y0193278*
X0120331Y019331*
X0120316Y019334*
X0120299Y019337*
X012028Y0193399*
X0120258Y0193426*
X0120235Y0193451*
X0120211Y0193475*
X0120184Y0193497*
X0120157Y0193517*
X0120128Y0193536*
X0120097Y0193552*
X0120066Y0193566*
X0120034Y0193577*
X0120001Y0193587*
X0119967Y0193594*
X0119933Y0193599*
X0119899Y0193601*
X0119864*
X011983Y0193599*
X0119796Y0193594*
X0119762Y0193587*
X0119729Y0193577*
X0119697Y0193566*
X0119666Y0193552*
X0119636Y0193536*
X0119606Y0193517*
X0119579Y0193497*
X0119552Y0193475*
X0119528Y0193451*
X0119505Y0193426*
X0119483Y0193399*
X0119464Y019337*
X0119447Y019334*
X0119432Y019331*
X0119419Y0193278*
X0119409Y0193245*
X01194Y0193212*
X0119394Y0193178*
X0119391Y0193144*
X011939Y019311*
X0119391Y0193075*
X0119394Y0193041*
X01194Y0193007*
X0119409Y0192974*
X0119419Y0192941*
X0119432Y0192909*
X0119447Y0192879*
X0119464Y0192849*
X0119483Y019282*
X0119505Y0192793*
X0119528Y0192768*
X0119552Y0192744*
X0119579Y0192722*
X0119606Y0192702*
X0119636Y0192683*
X0119666Y0192667*
X0119697Y0192653*
X0119729Y0192642*
X0119762Y0192632*
X0119796Y0192625*
X011983Y019262*
X0119864Y0192618*
X0119899*
X0119933Y019262*
X0119967Y0192625*
X0120001Y0192632*
X0120034Y0192642*
X0120066Y0192653*
X0120097Y0192667*
X0120128Y0192683*
X0120157Y0192702*
X0120184Y0192722*
X0120211Y0192744*
X0120235Y0192768*
X0120258Y0192793*
X012028Y019282*
X0120299Y0192849*
X0120316Y0192879*
X0120331Y0192909*
X0120344Y0192941*
X0120354Y0192974*
X0120363Y0193007*
X0120369Y0193041*
X0120372Y0193075*
X0120374Y019311*
G54D11*
X0051886Y0107661D02*
D01*
X0051883Y010773*
X0051876Y01078*
X0051864Y0107868*
X0051847Y0107936*
X0051825Y0108003*
X0051799Y0108067*
X0051768Y010813*
X0051734Y010819*
X0051695Y0108248*
X0051652Y0108303*
X0051605Y0108355*
X0051555Y0108404*
X0051501Y0108449*
X0051445Y010849*
X0051386Y0108527*
X0051324Y0108559*
X005126Y0108588*
X0051195Y0108612*
X0051127Y0108631*
X0051059Y0108645*
X005099Y0108655*
X005092Y010866*
X0050851*
X0050781Y0108655*
X0050712Y0108645*
X0050644Y0108631*
X0050576Y0108612*
X0050511Y0108588*
X0050447Y0108559*
X0050386Y0108527*
X0050326Y010849*
X005027Y0108449*
X0050216Y0108404*
X0050166Y0108355*
X0050119Y0108303*
X0050076Y0108248*
X0050037Y010819*
X0050003Y010813*
X0049972Y0108067*
X0049946Y0108003*
X0049924Y0107936*
X0049907Y0107868*
X0049895Y01078*
X0049888Y010773*
X0049886Y0107661*
X0049888Y0107591*
X0049895Y0107521*
X0049907Y0107453*
X0049924Y0107385*
X0049946Y0107318*
X0049972Y0107254*
X0050003Y0107191*
X0050037Y0107131*
X0050076Y0107073*
X0050119Y0107018*
X0050166Y0106966*
X0050216Y0106917*
X005027Y0106872*
X0050326Y0106831*
X0050386Y0106794*
X0050447Y0106762*
X0050511Y0106733*
X0050576Y0106709*
X0050644Y010669*
X0050712Y0106676*
X0050781Y0106666*
X0050851Y0106661*
X005092*
X005099Y0106666*
X0051059Y0106676*
X0051127Y010669*
X0051195Y0106709*
X005126Y0106733*
X0051324Y0106762*
X0051386Y0106794*
X0051445Y0106831*
X0051501Y0106872*
X0051555Y0106917*
X0051605Y0106966*
X0051652Y0107018*
X0051695Y0107073*
X0051734Y0107131*
X0051768Y0107191*
X0051799Y0107254*
X0051825Y0107318*
X0051847Y0107385*
X0051864Y0107453*
X0051876Y0107521*
X0051883Y0107591*
X0051886Y0107661*
X0052083Y0213567D02*
D01*
X005208Y0213636*
X0052073Y0213706*
X0052061Y0213774*
X0052044Y0213842*
X0052022Y0213909*
X0051996Y0213973*
X0051965Y0214036*
X0051931Y0214096*
X0051892Y0214154*
X0051849Y0214209*
X0051802Y0214261*
X0051752Y021431*
X0051698Y0214355*
X0051642Y0214396*
X0051583Y0214433*
X0051521Y0214465*
X0051457Y0214494*
X0051392Y0214518*
X0051324Y0214537*
X0051256Y0214551*
X0051187Y0214561*
X0051117Y0214566*
X0051048*
X0050978Y0214561*
X0050909Y0214551*
X0050841Y0214537*
X0050773Y0214518*
X0050708Y0214494*
X0050644Y0214465*
X0050583Y0214433*
X0050523Y0214396*
X0050467Y0214355*
X0050413Y021431*
X0050363Y0214261*
X0050316Y0214209*
X0050273Y0214154*
X0050234Y0214096*
X00502Y0214036*
X0050169Y0213973*
X0050143Y0213909*
X0050121Y0213842*
X0050104Y0213774*
X0050092Y0213706*
X0050085Y0213636*
X0050083Y0213567*
X0050085Y0213497*
X0050092Y0213427*
X0050104Y0213359*
X0050121Y0213291*
X0050143Y0213224*
X0050169Y021316*
X00502Y0213097*
X0050234Y0213037*
X0050273Y0212979*
X0050316Y0212924*
X0050363Y0212872*
X0050413Y0212823*
X0050467Y0212778*
X0050523Y0212737*
X0050583Y02127*
X0050644Y0212668*
X0050708Y0212639*
X0050773Y0212615*
X0050841Y0212596*
X0050909Y0212582*
X0050978Y0212572*
X0051048Y0212567*
X0051117*
X0051187Y0212572*
X0051256Y0212582*
X0051324Y0212596*
X0051392Y0212615*
X0051457Y0212639*
X0051521Y0212668*
X0051583Y02127*
X0051642Y0212737*
X0051698Y0212778*
X0051752Y0212823*
X0051802Y0212872*
X0051849Y0212924*
X0051892Y0212979*
X0051931Y0213037*
X0051965Y0213097*
X0051996Y021316*
X0052022Y0213224*
X0052044Y0213291*
X0052061Y0213359*
X0052073Y0213427*
X005208Y0213497*
X0052083Y0213567*
X015411Y038611D02*
D01*
X0154103Y0386284*
X0154085Y0386457*
X0154055Y0386629*
X0154013Y0386799*
X0153959Y0386965*
X0153893Y0387126*
X0153817Y0387283*
X015373Y0387434*
X0153632Y0387579*
X0153525Y0387716*
X0153408Y0387846*
X0153282Y0387967*
X0153149Y038808*
X0153007Y0388182*
X015286Y0388275*
X0152705Y0388356*
X0152546Y0388427*
X0152382Y0388487*
X0152214Y0388535*
X0152044Y0388572*
X0151871Y0388596*
X0151697Y0388608*
X0151522*
X0151348Y0388596*
X0151175Y0388572*
X0151005Y0388535*
X0150837Y0388487*
X0150673Y0388427*
X0150514Y0388356*
X015036Y0388275*
X0150212Y0388182*
X015007Y038808*
X0149937Y0387967*
X0149811Y0387846*
X0149694Y0387716*
X0149587Y0387579*
X0149489Y0387434*
X0149402Y0387283*
X0149326Y0387126*
X014926Y0386965*
X0149206Y0386799*
X0149164Y0386629*
X0149134Y0386457*
X0149116Y0386284*
X014911Y038611*
X0149116Y0385935*
X0149134Y0385762*
X0149164Y038559*
X0149206Y038542*
X014926Y0385254*
X0149326Y0385093*
X0149402Y0384936*
X0149489Y0384785*
X0149587Y038464*
X0149694Y0384503*
X0149811Y0384373*
X0149937Y0384252*
X015007Y0384139*
X0150212Y0384037*
X015036Y0383944*
X0150514Y0383863*
X0150673Y0383792*
X0150837Y0383732*
X0151005Y0383684*
X0151175Y0383647*
X0151348Y0383623*
X0151522Y0383611*
X0151697*
X0151871Y0383623*
X0152044Y0383647*
X0152214Y0383684*
X0152382Y0383732*
X0152546Y0383792*
X0152705Y0383863*
X015286Y0383944*
X0153007Y0384037*
X0153149Y0384139*
X0153282Y0384252*
X0153408Y0384373*
X0153525Y0384503*
X0153632Y038464*
X015373Y0384785*
X0153817Y0384936*
X0153893Y0385093*
X0153959Y0385254*
X0154013Y038542*
X0154055Y038559*
X0154085Y0385762*
X0154103Y0385935*
X015411Y038611*
X0107973Y0142421D02*
X0110531D01*
X01125Y0147736D02*
Y0149508D01*
X0107973Y0154823D02*
X0110531D01*
X0048425Y0125197D02*
X0061811D01*
Y0109055D02*
Y0125197D01*
X0048425Y0109055D02*
Y0125197D01*
Y0109055D02*
X0061713D01*
X0048622Y0231102D02*
X0062008D01*
Y0214961D02*
Y0231102D01*
X0048622Y0214961D02*
Y0231102D01*
Y0214961D02*
X006191D01*
X0047441Y0088386D02*
Y0092716D01*
X0206496Y0355906D02*
X0210433D01*
X0206496D02*
Y0357677D01*
Y0364567D02*
X0210433D01*
X0206496Y0362795D02*
Y0364567D01*
X0189567Y0054134D02*
Y0066339D01*
X0182087Y0054134D02*
Y0066339D01*
X0189075D02*
X0189567D01*
X0189075Y0054134D02*
X0189567D01*
X0182087Y0066339D02*
X0182579D01*
X0182087Y0054134D02*
X0182579D01*
X014161Y0390362D02*
X0157732D01*
X0205488D02*
X022161D01*
X0205488Y0426858D02*
X022161D01*
X014161D02*
X0157732D01*
X022161Y0390362D02*
Y0426858D01*
X014161Y0390362D02*
Y0426858D01*
X0541339Y0273091D02*
Y0292776D01*
X0548425Y0273091D02*
Y0292776D01*
X0541339D02*
X0548425D01*
X0541339Y0273091D02*
X0548425D01*
X0470472Y0272638D02*
Y0292323D01*
X0478346Y0272638D02*
Y0292323D01*
X0470472D02*
X0478346D01*
X0470472Y0272638D02*
X0478346D01*
X0548622Y0421181D02*
Y0431181D01*
X0508622Y0421181D02*
X0548622D01*
X0508622Y0431181D02*
X0548622D01*
X0508622Y0421181D02*
Y0431181D01*
X0315551Y0289764D02*
X0332087D01*
Y0275197D02*
Y0289764D01*
X0315551Y0275197D02*
X0332087D01*
X0315551D02*
Y0289764D01*
X0348228Y0288583D02*
X0358465D01*
X0348228Y0276378D02*
X0358465D01*
X029252Y0280819D02*
Y0282173D01*
X0297012Y0278346D02*
X0299445D01*
X0303937Y0280819D02*
Y0282173D01*
X0107776Y0102854D02*
X0110335D01*
X0112303Y0095768D02*
Y0097539D01*
X0107776Y0090453D02*
X0110335D01*
X0152854Y0355906D02*
X0156791D01*
X0152854D02*
Y0357677D01*
Y0364567D02*
X0156791D01*
X0152854Y0362795D02*
Y0364567D01*
X0170571Y0355906D02*
X0174508D01*
X0170571D02*
Y0357677D01*
Y0364567D02*
X0174508D01*
X0170571Y0362795D02*
Y0364567D01*
X0188779Y0355906D02*
X0192717D01*
X0188779D02*
Y0357677D01*
Y0364567D02*
X0192717D01*
X0188779Y0362795D02*
Y0364567D01*
X0047441Y019311D02*
Y0197441D01*
Y0245866D02*
Y0250197D01*
Y0141142D02*
Y0145472D01*
X0108957Y0243799D02*
X0111516D01*
X0106988Y0249114D02*
Y0250886D01*
X0108957Y0256201D02*
X0111516D01*
X0108957Y019065D02*
X0111516D01*
X0106988Y0195965D02*
Y0197736D01*
X0108957Y0203051D02*
X0111516D01*
G54D12*
X0189272Y0068307D02*
D01*
X0189271Y006832*
X018927Y0068334*
X0189267Y0068347*
X0189264Y0068361*
X018926Y0068374*
X0189254Y0068387*
X0189248Y0068399*
X0189242Y0068411*
X0189234Y0068422*
X0189225Y0068433*
X0189216Y0068443*
X0189206Y0068453*
X0189196Y0068462*
X0189185Y006847*
X0189173Y0068477*
X0189161Y0068484*
X0189148Y0068489*
X0189135Y0068494*
X0189122Y0068498*
X0189109Y0068501*
X0189095Y0068502*
X0189081Y0068503*
X0189068*
X0189054Y0068502*
X018904Y0068501*
X0189027Y0068498*
X0189014Y0068494*
X0189001Y0068489*
X0188988Y0068484*
X0188976Y0068477*
X0188964Y006847*
X0188953Y0068462*
X0188943Y0068453*
X0188933Y0068443*
X0188924Y0068433*
X0188915Y0068422*
X0188907Y0068411*
X0188901Y0068399*
X0188895Y0068387*
X0188889Y0068374*
X0188885Y0068361*
X0188882Y0068347*
X0188879Y0068334*
X0188878Y006832*
X0188878Y0068307*
X0188878Y0068293*
X0188879Y0068279*
X0188882Y0068266*
X0188885Y0068252*
X0188889Y0068239*
X0188895Y0068226*
X0188901Y0068214*
X0188907Y0068202*
X0188915Y0068191*
X0188924Y006818*
X0188933Y006817*
X0188943Y006816*
X0188953Y0068151*
X0188964Y0068143*
X0188976Y0068136*
X0188988Y0068129*
X0189001Y0068124*
X0189014Y0068119*
X0189027Y0068115*
X018904Y0068112*
X0189054Y0068111*
X0189068Y006811*
X0189081*
X0189095Y0068111*
X0189109Y0068112*
X0189122Y0068115*
X0189135Y0068119*
X0189148Y0068124*
X0189161Y0068129*
X0189173Y0068136*
X0189185Y0068143*
X0189196Y0068151*
X0189206Y006816*
X0189216Y006817*
X0189225Y006818*
X0189234Y0068191*
X0189242Y0068202*
X0189248Y0068214*
X0189254Y0068226*
X018926Y0068239*
X0189264Y0068252*
X0189267Y0068266*
X018927Y0068279*
X0189271Y0068293*
X0189272Y0068307*
X0122327Y0417587D02*
D01*
X0122326Y04176*
X0122325Y0417614*
X0122322Y0417627*
X0122319Y0417641*
X0122315Y0417654*
X0122309Y0417667*
X0122303Y0417679*
X0122297Y0417691*
X0122289Y0417702*
X012228Y0417713*
X0122271Y0417723*
X0122261Y0417733*
X0122251Y0417742*
X012224Y041775*
X0122228Y0417757*
X0122216Y0417764*
X0122203Y0417769*
X012219Y0417774*
X0122177Y0417778*
X0122164Y0417781*
X012215Y0417782*
X0122136Y0417783*
X0122123*
X0122109Y0417782*
X0122095Y0417781*
X0122082Y0417778*
X0122069Y0417774*
X0122056Y0417769*
X0122043Y0417764*
X0122031Y0417757*
X0122019Y041775*
X0122008Y0417742*
X0121998Y0417733*
X0121988Y0417723*
X0121979Y0417713*
X012197Y0417702*
X0121962Y0417691*
X0121956Y0417679*
X012195Y0417667*
X0121944Y0417654*
X012194Y0417641*
X0121937Y0417627*
X0121934Y0417614*
X0121933Y04176*
X0121933Y0417587*
X0121933Y0417573*
X0121934Y0417559*
X0121937Y0417546*
X012194Y0417532*
X0121944Y0417519*
X012195Y0417506*
X0121956Y0417494*
X0121962Y0417482*
X012197Y0417471*
X0121979Y041746*
X0121988Y041745*
X0121998Y041744*
X0122008Y0417431*
X0122019Y0417423*
X0122031Y0417416*
X0122043Y0417409*
X0122056Y0417404*
X0122069Y0417399*
X0122082Y0417395*
X0122095Y0417392*
X0122109Y0417391*
X0122123Y041739*
X0122136*
X012215Y0417391*
X0122164Y0417392*
X0122177Y0417395*
X012219Y0417399*
X0122203Y0417404*
X0122216Y0417409*
X0122228Y0417416*
X012224Y0417423*
X0122251Y0417431*
X0122261Y041744*
X0122271Y041745*
X012228Y041746*
X0122289Y0417471*
X0122297Y0417482*
X0122303Y0417494*
X0122309Y0417506*
X0122315Y0417519*
X0122319Y0417532*
X0122322Y0417546*
X0122325Y0417559*
X0122326Y0417573*
X0122327Y0417587*
X0622342Y0290059D02*
D01*
X0622341Y0290072*
X062234Y0290086*
X0622337Y0290099*
X0622334Y0290113*
X062233Y0290126*
X0622324Y0290139*
X0622318Y0290151*
X0622312Y0290163*
X0622304Y0290174*
X0622295Y0290185*
X0622286Y0290195*
X0622276Y0290205*
X0622266Y0290214*
X0622255Y0290222*
X0622243Y0290229*
X0622231Y0290236*
X0622218Y0290241*
X0622205Y0290246*
X0622192Y029025*
X0622179Y0290253*
X0622165Y0290254*
X0622151Y0290255*
X0622138*
X0622124Y0290254*
X062211Y0290253*
X0622097Y029025*
X0622084Y0290246*
X0622071Y0290241*
X0622058Y0290236*
X0622046Y0290229*
X0622034Y0290222*
X0622023Y0290214*
X0622013Y0290205*
X0622003Y0290195*
X0621994Y0290185*
X0621985Y0290174*
X0621977Y0290163*
X0621971Y0290151*
X0621965Y0290139*
X0621959Y0290126*
X0621955Y0290113*
X0621952Y0290099*
X0621949Y0290086*
X0621948Y0290072*
X0621948Y0290059*
X0621948Y0290045*
X0621949Y0290031*
X0621952Y0290018*
X0621955Y0290004*
X0621959Y0289991*
X0621965Y0289978*
X0621971Y0289966*
X0621977Y0289954*
X0621985Y0289943*
X0621994Y0289932*
X0622003Y0289922*
X0622013Y0289912*
X0622023Y0289903*
X0622034Y0289895*
X0622046Y0289888*
X0622058Y0289881*
X0622071Y0289876*
X0622084Y0289871*
X0622097Y0289867*
X062211Y0289864*
X0622124Y0289863*
X0622138Y0289862*
X0622151*
X0622165Y0289863*
X0622179Y0289864*
X0622192Y0289867*
X0622205Y0289871*
X0622218Y0289876*
X0622231Y0289881*
X0622243Y0289888*
X0622255Y0289895*
X0622266Y0289903*
X0622276Y0289912*
X0622286Y0289922*
X0622295Y0289932*
X0622304Y0289943*
X0622312Y0289954*
X0622318Y0289966*
X0622324Y0289978*
X062233Y0289991*
X0622334Y0290004*
X0622337Y0290018*
X062234Y0290031*
X0622341Y0290045*
X0622342Y0290059*
X0061827Y0417587D02*
D01*
X0061826Y04176*
X0061825Y0417614*
X0061822Y0417627*
X0061819Y0417641*
X0061815Y0417654*
X0061809Y0417667*
X0061803Y0417679*
X0061797Y0417691*
X0061789Y0417702*
X006178Y0417713*
X0061771Y0417723*
X0061761Y0417733*
X0061751Y0417742*
X006174Y041775*
X0061728Y0417757*
X0061716Y0417764*
X0061703Y0417769*
X006169Y0417774*
X0061677Y0417778*
X0061664Y0417781*
X006165Y0417782*
X0061636Y0417783*
X0061623*
X0061609Y0417782*
X0061595Y0417781*
X0061582Y0417778*
X0061569Y0417774*
X0061556Y0417769*
X0061543Y0417764*
X0061531Y0417757*
X0061519Y041775*
X0061508Y0417742*
X0061498Y0417733*
X0061488Y0417723*
X0061479Y0417713*
X006147Y0417702*
X0061462Y0417691*
X0061456Y0417679*
X006145Y0417667*
X0061444Y0417654*
X006144Y0417641*
X0061437Y0417627*
X0061434Y0417614*
X0061433Y04176*
X0061433Y0417587*
X0061433Y0417573*
X0061434Y0417559*
X0061437Y0417546*
X006144Y0417532*
X0061444Y0417519*
X006145Y0417506*
X0061456Y0417494*
X0061462Y0417482*
X006147Y0417471*
X0061479Y041746*
X0061488Y041745*
X0061498Y041744*
X0061508Y0417431*
X0061519Y0417423*
X0061531Y0417416*
X0061543Y0417409*
X0061556Y0417404*
X0061569Y0417399*
X0061582Y0417395*
X0061595Y0417392*
X0061609Y0417391*
X0061623Y041739*
X0061636*
X006165Y0417391*
X0061664Y0417392*
X0061677Y0417395*
X006169Y0417399*
X0061703Y0417404*
X0061716Y0417409*
X0061728Y0417416*
X006174Y0417423*
X0061751Y0417431*
X0061761Y041744*
X0061771Y041745*
X006178Y041746*
X0061789Y0417471*
X0061797Y0417482*
X0061803Y0417494*
X0061809Y0417506*
X0061815Y0417519*
X0061819Y0417532*
X0061822Y0417546*
X0061825Y0417559*
X0061826Y0417573*
X0061827Y0417587*
X0081993D02*
D01*
X0081992Y04176*
X0081991Y0417614*
X0081988Y0417627*
X0081985Y0417641*
X0081981Y0417654*
X0081975Y0417667*
X0081969Y0417679*
X0081963Y0417691*
X0081955Y0417702*
X0081946Y0417713*
X0081937Y0417723*
X0081927Y0417733*
X0081917Y0417742*
X0081906Y041775*
X0081894Y0417757*
X0081882Y0417764*
X0081869Y0417769*
X0081856Y0417774*
X0081843Y0417778*
X008183Y0417781*
X0081816Y0417782*
X0081802Y0417783*
X0081789*
X0081775Y0417782*
X0081761Y0417781*
X0081748Y0417778*
X0081735Y0417774*
X0081722Y0417769*
X0081709Y0417764*
X0081697Y0417757*
X0081685Y041775*
X0081674Y0417742*
X0081664Y0417733*
X0081654Y0417723*
X0081645Y0417713*
X0081636Y0417702*
X0081628Y0417691*
X0081622Y0417679*
X0081616Y0417667*
X008161Y0417654*
X0081606Y0417641*
X0081603Y0417627*
X00816Y0417614*
X0081599Y04176*
X0081599Y0417587*
X0081599Y0417573*
X00816Y0417559*
X0081603Y0417546*
X0081606Y0417532*
X008161Y0417519*
X0081616Y0417506*
X0081622Y0417494*
X0081628Y0417482*
X0081636Y0417471*
X0081645Y041746*
X0081654Y041745*
X0081664Y041744*
X0081674Y0417431*
X0081685Y0417423*
X0081697Y0417416*
X0081709Y0417409*
X0081722Y0417404*
X0081735Y0417399*
X0081748Y0417395*
X0081761Y0417392*
X0081775Y0417391*
X0081789Y041739*
X0081802*
X0081816Y0417391*
X008183Y0417392*
X0081843Y0417395*
X0081856Y0417399*
X0081869Y0417404*
X0081882Y0417409*
X0081894Y0417416*
X0081906Y0417423*
X0081917Y0417431*
X0081927Y041744*
X0081937Y041745*
X0081946Y041746*
X0081955Y0417471*
X0081963Y0417482*
X0081969Y0417494*
X0081975Y0417506*
X0081981Y0417519*
X0081985Y0417532*
X0081988Y0417546*
X0081991Y0417559*
X0081992Y0417573*
X0081993Y0417587*
X010216D02*
D01*
X0102159Y04176*
X0102158Y0417614*
X0102155Y0417627*
X0102152Y0417641*
X0102148Y0417654*
X0102142Y0417667*
X0102136Y0417679*
X010213Y0417691*
X0102122Y0417702*
X0102113Y0417713*
X0102104Y0417723*
X0102094Y0417733*
X0102084Y0417742*
X0102073Y041775*
X0102061Y0417757*
X0102049Y0417764*
X0102036Y0417769*
X0102023Y0417774*
X010201Y0417778*
X0101997Y0417781*
X0101983Y0417782*
X0101969Y0417783*
X0101956*
X0101942Y0417782*
X0101928Y0417781*
X0101915Y0417778*
X0101902Y0417774*
X0101889Y0417769*
X0101876Y0417764*
X0101864Y0417757*
X0101852Y041775*
X0101841Y0417742*
X0101831Y0417733*
X0101821Y0417723*
X0101812Y0417713*
X0101803Y0417702*
X0101795Y0417691*
X0101789Y0417679*
X0101783Y0417667*
X0101777Y0417654*
X0101773Y0417641*
X010177Y0417627*
X0101767Y0417614*
X0101766Y04176*
X0101766Y0417587*
X0101766Y0417573*
X0101767Y0417559*
X010177Y0417546*
X0101773Y0417532*
X0101777Y0417519*
X0101783Y0417506*
X0101789Y0417494*
X0101795Y0417482*
X0101803Y0417471*
X0101812Y041746*
X0101821Y041745*
X0101831Y041744*
X0101841Y0417431*
X0101852Y0417423*
X0101864Y0417416*
X0101876Y0417409*
X0101889Y0417404*
X0101902Y0417399*
X0101915Y0417395*
X0101928Y0417392*
X0101942Y0417391*
X0101956Y041739*
X0101969*
X0101983Y0417391*
X0101997Y0417392*
X010201Y0417395*
X0102023Y0417399*
X0102036Y0417404*
X0102049Y0417409*
X0102061Y0417416*
X0102073Y0417423*
X0102084Y0417431*
X0102094Y041744*
X0102104Y041745*
X0102113Y041746*
X0102122Y0417471*
X010213Y0417482*
X0102136Y0417494*
X0102142Y0417506*
X0102148Y0417519*
X0102152Y0417532*
X0102155Y0417546*
X0102158Y0417559*
X0102159Y0417573*
X010216Y0417587*
G54D13*
X0413896Y0158893D02*
D01*
X0413894Y0158927*
X0413891Y0158962*
X0413885Y0158996*
X0413876Y015903*
X0413865Y0159064*
X0413852Y0159096*
X0413837Y0159127*
X041382Y0159157*
X04138Y0159186*
X0413779Y0159214*
X0413755Y015924*
X041373Y0159264*
X0413703Y0159287*
X0413675Y0159307*
X0413646Y0159326*
X0413615Y0159342*
X0413583Y0159356*
X041355Y0159368*
X0413516Y0159378*
X0413482Y0159385*
X0413448Y015939*
X0413413Y0159392*
X0413378*
X0413343Y015939*
X0413309Y0159385*
X0413275Y0159378*
X0413241Y0159368*
X0413208Y0159356*
X0413176Y0159342*
X0413146Y0159326*
X0413116Y0159307*
X0413088Y0159287*
X0413061Y0159264*
X0413036Y015924*
X0413012Y0159214*
X0412991Y0159186*
X0412971Y0159157*
X0412954Y0159127*
X0412939Y0159096*
X0412926Y0159064*
X0412915Y015903*
X0412906Y0158996*
X04129Y0158962*
X0412897Y0158927*
X0412896Y0158893*
X0412897Y0158858*
X04129Y0158823*
X0412906Y0158789*
X0412915Y0158755*
X0412926Y0158721*
X0412939Y0158689*
X0412954Y0158658*
X0412971Y0158628*
X0412991Y0158599*
X0413012Y0158571*
X0413036Y0158545*
X0413061Y0158521*
X0413088Y0158498*
X0413116Y0158478*
X0413146Y0158459*
X0413176Y0158443*
X0413208Y0158429*
X0413241Y0158417*
X0413275Y0158407*
X0413309Y01584*
X0413343Y0158395*
X0413378Y0158393*
X0413413*
X0413448Y0158395*
X0413482Y01584*
X0413516Y0158407*
X041355Y0158417*
X0413583Y0158429*
X0413615Y0158443*
X0413646Y0158459*
X0413675Y0158478*
X0413703Y0158498*
X041373Y0158521*
X0413755Y0158545*
X0413779Y0158571*
X04138Y0158599*
X041382Y0158628*
X0413837Y0158658*
X0413852Y0158689*
X0413865Y0158721*
X0413876Y0158755*
X0413885Y0158789*
X0413891Y0158823*
X0413894Y0158858*
X0413896Y0158893*
X0578809Y0067913D02*
Y0267913D01*
X0378809Y0067913D02*
X0578809D01*
X0378809D02*
Y0267913D01*
X0578809*
X0693181Y0234803D02*
Y0287409D01*
X0642787Y0234803D02*
X0693181D01*
X0642787D02*
Y0287409D01*
X0693181*
X0230974Y0430984D02*
X0495463D01*
Y0305984D02*
Y0430984D01*
X0230974Y0305984D02*
X0495463D01*
X0230974D02*
Y0430984D01*
X0606787Y0138803D02*
X0657181D01*
Y0191409*
X0606787D02*
X0657181D01*
X0606787Y0138803D02*
Y0191409D01*
X0354305Y0218441D02*
X0356304D01*
X0355304*
Y0224439*
X0354305Y0223439*
X0210803Y024094D02*
X0206804D01*
X0210803Y0244939*
Y0245939*
X0209804Y0246939*
X0207804*
X0206804Y0245939*
X0166805Y0223439D02*
X0167804Y0224439D01*
X0169804*
X0170803Y0223439*
Y0222439*
X0169804Y022144*
X0168804*
X0169804*
X0170803Y022044*
Y021944*
X0169804Y0218441*
X0167804*
X0166805Y021944*
X0209804Y0093441D02*
Y0099439D01*
X0206804Y0096439*
X0210803*
G54D14*
X0545276Y0289626D02*
D01*
X0545274Y028968*
X0545268Y0289735*
X0545258Y0289789*
X0545245Y0289842*
X0545228Y0289895*
X0545207Y0289946*
X0545183Y0289995*
X0545156Y0290043*
X0545125Y0290088*
X0545091Y0290131*
X0545055Y0290172*
X0545015Y029021*
X0544973Y0290246*
X0544929Y0290278*
X0544882Y0290307*
X0544833Y0290333*
X0544783Y0290355*
X0544732Y0290374*
X0544679Y0290389*
X0544625Y0290401*
X0544571Y0290408*
X0544516Y0290412*
X0544461*
X0544406Y0290408*
X0544352Y0290401*
X0544298Y0290389*
X0544245Y0290374*
X0544194Y0290355*
X0544144Y0290333*
X0544095Y0290307*
X0544048Y0290278*
X0544004Y0290246*
X0543962Y029021*
X0543922Y0290172*
X0543886Y0290131*
X0543852Y0290088*
X0543821Y0290043*
X0543794Y0289995*
X054377Y0289946*
X0543749Y0289895*
X0543732Y0289842*
X0543719Y0289789*
X0543709Y0289735*
X0543703Y028968*
X0543702Y0289626*
X0543703Y0289571*
X0543709Y0289516*
X0543719Y0289462*
X0543732Y0289409*
X0543749Y0289356*
X054377Y0289305*
X0543794Y0289256*
X0543821Y0289208*
X0543852Y0289163*
X0543886Y028912*
X0543922Y0289079*
X0543962Y0289041*
X0544004Y0289005*
X0544048Y0288973*
X0544095Y0288944*
X0544144Y0288918*
X0544194Y0288896*
X0544245Y0288877*
X0544298Y0288862*
X0544352Y028885*
X0544406Y0288843*
X0544461Y0288839*
X0544516*
X0544571Y0288843*
X0544625Y028885*
X0544679Y0288862*
X0544732Y0288877*
X0544783Y0288896*
X0544833Y0288918*
X0544882Y0288944*
X0544929Y0288973*
X0544973Y0289005*
X0545015Y0289041*
X0545055Y0289079*
X0545091Y028912*
X0545125Y0289163*
X0545156Y0289208*
X0545183Y0289256*
X0545207Y0289305*
X0545228Y0289356*
X0545245Y0289409*
X0545258Y0289462*
X0545268Y0289516*
X0545274Y0289571*
X0545276Y0289626*
X0474409Y0289173D02*
D01*
X0474407Y0289227*
X0474401Y0289282*
X0474391Y0289336*
X0474378Y0289389*
X0474361Y0289442*
X047434Y0289493*
X0474316Y0289542*
X0474289Y028959*
X0474258Y0289635*
X0474224Y0289678*
X0474188Y0289719*
X0474148Y0289757*
X0474106Y0289793*
X0474062Y0289825*
X0474015Y0289854*
X0473966Y028988*
X0473916Y0289902*
X0473865Y0289921*
X0473812Y0289936*
X0473758Y0289948*
X0473704Y0289955*
X0473649Y0289959*
X0473594*
X0473539Y0289955*
X0473485Y0289948*
X0473431Y0289936*
X0473378Y0289921*
X0473327Y0289902*
X0473277Y028988*
X0473228Y0289854*
X0473181Y0289825*
X0473137Y0289793*
X0473095Y0289757*
X0473055Y0289719*
X0473019Y0289678*
X0472985Y0289635*
X0472954Y028959*
X0472927Y0289542*
X0472903Y0289493*
X0472882Y0289442*
X0472865Y0289389*
X0472852Y0289336*
X0472842Y0289282*
X0472836Y0289227*
X0472835Y0289173*
X0472836Y0289118*
X0472842Y0289063*
X0472852Y0289009*
X0472865Y0288956*
X0472882Y0288903*
X0472903Y0288852*
X0472927Y0288803*
X0472954Y0288755*
X0472985Y028871*
X0473019Y0288667*
X0473055Y0288626*
X0473095Y0288588*
X0473137Y0288552*
X0473181Y028852*
X0473228Y0288491*
X0473277Y0288465*
X0473327Y0288443*
X0473378Y0288424*
X0473431Y0288409*
X0473485Y0288397*
X0473539Y028839*
X0473594Y0288386*
X0473649*
X0473704Y028839*
X0473758Y0288397*
X0473812Y0288409*
X0473865Y0288424*
X0473916Y0288443*
X0473966Y0288465*
X0474015Y0288491*
X0474062Y028852*
X0474106Y0288552*
X0474148Y0288588*
X0474188Y0288626*
X0474224Y0288667*
X0474258Y028871*
X0474289Y0288755*
X0474316Y0288803*
X047434Y0288852*
X0474361Y0288903*
X0474378Y0288956*
X0474391Y0289009*
X0474401Y0289063*
X0474407Y0289118*
X0474409Y0289173*
G54D15*
X0344124Y0208822D02*
D01*
X0344122Y0208876*
X0344116Y0208931*
X0344106Y0208985*
X0344093Y0209039*
X0344076Y0209091*
X0344055Y0209142*
X0344031Y0209191*
X0344004Y0209239*
X0343973Y0209285*
X0343939Y0209328*
X0343902Y0209369*
X0343863Y0209407*
X0343821Y0209442*
X0343776Y0209475*
X034373Y0209504*
X0343681Y020953*
X0343631Y0209552*
X0343579Y0209571*
X0343526Y0209586*
X0343472Y0209598*
X0343418Y0209605*
X0343363Y0209609*
X0343308*
X0343253Y0209605*
X0343199Y0209598*
X0343145Y0209586*
X0343092Y0209571*
X034304Y0209552*
X034299Y020953*
X0342942Y0209504*
X0342895Y0209475*
X034285Y0209442*
X0342808Y0209407*
X0342769Y0209369*
X0342732Y0209328*
X0342698Y0209285*
X0342667Y0209239*
X034264Y0209191*
X0342616Y0209142*
X0342595Y0209091*
X0342578Y0209039*
X0342565Y0208985*
X0342555Y0208931*
X0342549Y0208876*
X0342548Y0208822*
X0342549Y0208767*
X0342555Y0208712*
X0342565Y0208658*
X0342578Y0208604*
X0342595Y0208552*
X0342616Y0208501*
X034264Y0208452*
X0342667Y0208404*
X0342698Y0208358*
X0342732Y0208315*
X0342769Y0208274*
X0342808Y0208236*
X034285Y0208201*
X0342895Y0208168*
X0342942Y0208139*
X034299Y0208113*
X034304Y0208091*
X0343092Y0208072*
X0343145Y0208057*
X0343199Y0208045*
X0343253Y0208038*
X0343308Y0208034*
X0343363*
X0343418Y0208038*
X0343472Y0208045*
X0343526Y0208057*
X0343579Y0208072*
X0343631Y0208091*
X0343681Y0208113*
X034373Y0208139*
X0343776Y0208168*
X0343821Y0208201*
X0343863Y0208236*
X0343902Y0208274*
X0343939Y0208315*
X0343973Y0208358*
X0344004Y0208404*
X0344031Y0208452*
X0344055Y0208501*
X0344076Y0208552*
X0344093Y0208604*
X0344106Y0208658*
X0344116Y0208712*
X0344122Y0208767*
X0344124Y0208822*
X0221947Y023004D02*
D01*
X0221945Y0230094*
X0221939Y0230149*
X0221929Y0230203*
X0221916Y0230257*
X0221899Y0230309*
X0221878Y023036*
X0221854Y0230409*
X0221827Y0230457*
X0221796Y0230503*
X0221762Y0230546*
X0221725Y0230587*
X0221686Y0230625*
X0221644Y023066*
X0221599Y0230693*
X0221553Y0230722*
X0221504Y0230748*
X0221454Y023077*
X0221402Y0230789*
X0221349Y0230804*
X0221295Y0230816*
X0221241Y0230823*
X0221186Y0230827*
X0221131*
X0221076Y0230823*
X0221022Y0230816*
X0220968Y0230804*
X0220915Y0230789*
X0220863Y023077*
X0220813Y0230748*
X0220765Y0230722*
X0220718Y0230693*
X0220673Y023066*
X0220631Y0230625*
X0220592Y0230587*
X0220555Y0230546*
X0220521Y0230503*
X022049Y0230457*
X0220463Y0230409*
X0220439Y023036*
X0220418Y0230309*
X0220401Y0230257*
X0220388Y0230203*
X0220378Y0230149*
X0220372Y0230094*
X0220371Y023004*
X0220372Y0229985*
X0220378Y022993*
X0220388Y0229876*
X0220401Y0229822*
X0220418Y022977*
X0220439Y0229719*
X0220463Y022967*
X022049Y0229622*
X0220521Y0229576*
X0220555Y0229533*
X0220592Y0229492*
X0220631Y0229454*
X0220673Y0229419*
X0220718Y0229386*
X0220765Y0229357*
X0220813Y0229331*
X0220863Y0229309*
X0220915Y022929*
X0220968Y0229275*
X0221022Y0229263*
X0221076Y0229256*
X0221131Y0229252*
X0221186*
X0221241Y0229256*
X0221295Y0229263*
X0221349Y0229275*
X0221402Y022929*
X0221454Y0229309*
X0221504Y0229331*
X0221553Y0229357*
X0221599Y0229386*
X0221644Y0229419*
X0221686Y0229454*
X0221725Y0229492*
X0221762Y0229533*
X0221796Y0229576*
X0221827Y0229622*
X0221854Y022967*
X0221878Y0229719*
X0221899Y022977*
X0221916Y0229822*
X0221929Y0229876*
X0221939Y022993*
X0221945Y0229985*
X0221947Y023004*
X0184232Y0131853D02*
D01*
X018423Y0131907*
X0184224Y0131962*
X0184214Y0132016*
X0184201Y013207*
X0184184Y0132122*
X0184163Y0132173*
X0184139Y0132222*
X0184112Y013227*
X0184081Y0132316*
X0184047Y0132359*
X018401Y01324*
X0183971Y0132438*
X0183929Y0132473*
X0183884Y0132506*
X0183838Y0132535*
X0183789Y0132561*
X0183739Y0132583*
X0183687Y0132602*
X0183634Y0132617*
X018358Y0132629*
X0183526Y0132636*
X0183471Y013264*
X0183416*
X0183361Y0132636*
X0183307Y0132629*
X0183253Y0132617*
X01832Y0132602*
X0183148Y0132583*
X0183098Y0132561*
X018305Y0132535*
X0183003Y0132506*
X0182958Y0132473*
X0182916Y0132438*
X0182877Y01324*
X018284Y0132359*
X0182806Y0132316*
X0182775Y013227*
X0182748Y0132222*
X0182724Y0132173*
X0182703Y0132122*
X0182686Y013207*
X0182673Y0132016*
X0182663Y0131962*
X0182657Y0131907*
X0182656Y0131853*
X0182657Y0131798*
X0182663Y0131743*
X0182673Y0131689*
X0182686Y0131635*
X0182703Y0131583*
X0182724Y0131532*
X0182748Y0131483*
X0182775Y0131435*
X0182806Y0131389*
X018284Y0131346*
X0182877Y0131305*
X0182916Y0131267*
X0182958Y0131232*
X0183003Y0131199*
X018305Y013117*
X0183098Y0131144*
X0183148Y0131122*
X01832Y0131103*
X0183253Y0131088*
X0183307Y0131076*
X0183361Y0131069*
X0183416Y0131065*
X0183471*
X0183526Y0131069*
X018358Y0131076*
X0183634Y0131088*
X0183687Y0131103*
X0183739Y0131122*
X0183789Y0131144*
X0183838Y013117*
X0183884Y0131199*
X0183929Y0131232*
X0183971Y0131267*
X018401Y0131305*
X0184047Y0131346*
X0184081Y0131389*
X0184112Y0131435*
X0184139Y0131483*
X0184163Y0131532*
X0184184Y0131583*
X0184201Y0131635*
X0184214Y0131689*
X0184224Y0131743*
X018423Y0131798*
X0184232Y0131853*
X029892Y0109645D02*
D01*
X0298918Y0109699*
X0298912Y0109754*
X0298902Y0109808*
X0298889Y0109862*
X0298872Y0109914*
X0298851Y0109965*
X0298827Y0110014*
X02988Y0110062*
X0298769Y0110108*
X0298735Y0110151*
X0298698Y0110192*
X0298659Y011023*
X0298617Y0110265*
X0298572Y0110298*
X0298526Y0110327*
X0298477Y0110353*
X0298427Y0110375*
X0298375Y0110394*
X0298322Y0110409*
X0298268Y0110421*
X0298214Y0110428*
X0298159Y0110432*
X0298104*
X0298049Y0110428*
X0297995Y0110421*
X0297941Y0110409*
X0297888Y0110394*
X0297836Y0110375*
X0297786Y0110353*
X0297738Y0110327*
X0297691Y0110298*
X0297646Y0110265*
X0297604Y011023*
X0297565Y0110192*
X0297528Y0110151*
X0297494Y0110108*
X0297463Y0110062*
X0297436Y0110014*
X0297412Y0109965*
X0297391Y0109914*
X0297374Y0109862*
X0297361Y0109808*
X0297351Y0109754*
X0297345Y0109699*
X0297344Y0109645*
X0297345Y010959*
X0297351Y0109535*
X0297361Y0109481*
X0297374Y0109427*
X0297391Y0109375*
X0297412Y0109324*
X0297436Y0109275*
X0297463Y0109227*
X0297494Y0109181*
X0297528Y0109138*
X0297565Y0109097*
X0297604Y0109059*
X0297646Y0109024*
X0297691Y0108991*
X0297738Y0108962*
X0297786Y0108936*
X0297836Y0108914*
X0297888Y0108895*
X0297941Y010888*
X0297995Y0108868*
X0298049Y0108861*
X0298104Y0108857*
X0298159*
X0298214Y0108861*
X0298268Y0108868*
X0298322Y010888*
X0298375Y0108895*
X0298427Y0108914*
X0298477Y0108936*
X0298526Y0108962*
X0298572Y0108991*
X0298617Y0109024*
X0298659Y0109059*
X0298698Y0109097*
X0298735Y0109138*
X0298769Y0109181*
X02988Y0109227*
X0298827Y0109275*
X0298851Y0109324*
X0298872Y0109375*
X0298889Y0109427*
X0298902Y0109481*
X0298912Y0109535*
X0298918Y010959*
X029892Y0109645*
G54D16*
X061761Y0241449D02*
X0633358D01*
X061761Y0221764D02*
X063887D01*
X066561Y0185764D02*
X0681358D01*
X0660098Y0205449D02*
X0681358D01*
G54D17*
X0198772Y0375D02*
X0204772D01*
X0610316Y0246106D02*
X0614253D01*
X019252Y0064527D02*
X0196457D01*
X0355953Y0068806D02*
X0361953D01*
X0355953Y0076406D02*
X0361953D01*
X0649184Y0196106D02*
Y0201106D01*
X0654784Y0196106D02*
Y0201106D01*
X0205768Y0063535D02*
Y0069535D01*
X0198169Y0063535D02*
Y0069535D01*
X0644184Y0224606D02*
Y0229606D01*
X0649784Y0224606D02*
Y0229606D01*
X0629684Y0211606D02*
Y0217606D01*
X0637284Y0211606D02*
Y0217606D01*
X0669784Y0210106D02*
Y0216106D01*
X0662184Y0210106D02*
Y0216106D01*
X0631359Y0282827D02*
Y0288827D01*
X0623759Y0282827D02*
Y0288827D01*
X0640021Y0282827D02*
Y0288827D01*
X063242Y0282827D02*
Y0288827D01*
X0663484Y0145906D02*
X0669484D01*
X0663484Y0138306D02*
X0669484D01*
X0663484Y0156906D02*
X0669484D01*
X0663484Y0149306D02*
X0669484D01*
X0299076Y0333221D02*
Y033922D01*
X0291476Y0333221D02*
Y033922D01*
X0258011Y0314913D02*
Y0320913D01*
X0265611Y0314913D02*
Y0320913D01*
X0611024Y0283465D02*
X0614961D01*
X0673016Y0211606D02*
X0676953D01*
X0621516Y0215606D02*
X0625453D01*
X0686984Y0179638D02*
Y0183575D01*
X0676378Y0179921D02*
Y0183858D01*
X0633858Y0244094D02*
Y0248031D01*
X0698032Y0190551D02*
X0701968D01*
X0598425Y0236221D02*
X0602362D01*
X0158417Y0375D02*
X0164417D01*
X016826D02*
X017426D01*
X0178102D02*
X0184102D01*
X0141969Y0149606D02*
Y0153543D01*
G54D18*
X0155044Y0081539D02*
Y0258705D01*
X0371581Y0081539D02*
Y0258705D01*
X0155044Y0081539D02*
X0371581D01*
X0155044Y0258705D02*
X0371581D01*
G54D19*
X0349261Y0128209D02*
Y0130835D01*
Y0128209D02*
X0351624D01*
Y0126044D02*
Y0128209D01*
Y0126044D02*
X0362648D01*
Y0128209*
X0365009*
Y0130835*
X0349261Y0209836D02*
Y0212461D01*
X0351624*
Y0214627*
X0362648*
Y0212461D02*
Y0214627D01*
Y0212461D02*
X0365009D01*
Y0209836D02*
Y0212461D01*
X0217518Y0251713D02*
X0220145D01*
X0217518Y0249352D02*
Y0251713D01*
X0215353Y0249352D02*
X0217518D01*
X0215353Y0238328D02*
Y0249352D01*
Y0238328D02*
X0217518D01*
Y0235965D02*
Y0238328D01*
Y0235965D02*
X0220145D01*
X0299145Y0251713D02*
X030177D01*
Y0249352D02*
Y0251713D01*
Y0249352D02*
X0303936D01*
Y0238328D02*
Y0249352D01*
X030177Y0238328D02*
X0303936D01*
X030177Y0235965D02*
Y0238328D01*
X0299145Y0235965D02*
X030177D01*
X0177518Y020984D02*
Y0212466D01*
X0175156D02*
X0177518D01*
X0175156D02*
Y0214631D01*
X0164132D02*
X0175156D01*
X0164132Y0212466D02*
Y0214631D01*
X016177Y0212466D02*
X0164132D01*
X016177Y020984D02*
Y0212466D01*
X0177518Y0128214D02*
Y013084D01*
X0175156Y0128214D02*
X0177518D01*
X0175156Y0126049D02*
Y0128214D01*
X0164132Y0126049D02*
X0175156D01*
X0164132D02*
Y0128214D01*
X016177D02*
X0164132D01*
X016177D02*
Y013084D01*
X0217519Y0103719D02*
X0220146D01*
X0217519Y0101357D02*
Y0103719D01*
X0215354Y0101357D02*
X0217519D01*
X0215354Y0090333D02*
Y0101357D01*
Y0090333D02*
X0217519D01*
Y0087972D02*
Y0090333D01*
Y0087972D02*
X0220146D01*
X0299146Y0103719D02*
X0301771D01*
Y0101357D02*
Y0103719D01*
Y0101357D02*
X0303937D01*
Y0090333D02*
Y0101357D01*
X0301771Y0090333D02*
X0303937D01*
X0301771Y0087972D02*
Y0090333D01*
X0299146Y0087972D02*
X0301771D01*
G54D20*
X0002984Y0262106D02*
X0006984Y0266106D01*
X0009984*
X0002984Y0234106D02*
X0006984Y0230106D01*
X0009984*
Y0266106D02*
X0037984D01*
Y0258106D02*
Y0266106D01*
X0009984Y0230106D02*
X0037984D01*
Y0238106*
Y0072606D02*
Y0080606D01*
X0009984Y0072606D02*
X0037984D01*
Y0100606D02*
Y0108606D01*
X0009984D02*
X0037984D01*
X0006984Y0072606D02*
X0009984D01*
X0002984Y0076606D02*
X0006984Y0072606D01*
Y0108606D02*
X0009984D01*
X0002984Y0104606D02*
X0006984Y0108606D01*
X0037984Y0125106D02*
Y0133106D01*
X0009984Y0125106D02*
X0037984D01*
Y0153106D02*
Y0161106D01*
X0009984D02*
X0037984D01*
X0006984Y0125106D02*
X0009984D01*
X0002984Y0129106D02*
X0006984Y0125106D01*
Y0161106D02*
X0009984D01*
X0002984Y0157106D02*
X0006984Y0161106D01*
X0037984Y0177606D02*
Y0185606D01*
X0009984Y0177606D02*
X0037984D01*
Y0205606D02*
Y0213606D01*
X0009984D02*
X0037984D01*
X0006984Y0177606D02*
X0009984D01*
X0002984Y0181606D02*
X0006984Y0177606D01*
Y0213606D02*
X0009984D01*
X0002984Y0209606D02*
X0006984Y0213606D01*
G54D21*
X0056556Y0213114D02*
Y0210115D01*
X0058055*
X0058555Y0210614*
Y0212614*
X0058055Y0213114*
X0056556*
X0061554Y0210115D02*
X0059555D01*
X0061554Y0212114*
Y0212614*
X0061054Y0213114*
X0060055*
X0059555Y0212614*
X005804Y0107799D02*
Y01048D01*
X005954*
X0060039Y0105299*
Y0107299*
X005954Y0107799*
X005804*
X0061039Y01048D02*
X0062039D01*
X0061539*
Y0107799*
X0061039Y0107299*
X0238704Y0283403D02*
X0235705D01*
Y0284902*
X0236205Y0285402*
X0237205*
X0237705Y0284902*
Y0283403*
Y0284403D02*
X0238704Y0285402D01*
Y0288401D02*
Y0286402D01*
X0236705Y0288401*
X0236205*
X0235705Y0287901*
Y0286902*
X0236205Y0286402*
X0235705Y0289401D02*
Y02914D01*
X0236205*
X0238204Y0289401*
X0238704*
X0244723Y0283084D02*
X0241724D01*
Y0284584*
X0242224Y0285083*
X0243224*
X0243724Y0284584*
Y0283084*
Y0284084D02*
X0244723Y0285083D01*
Y0288083D02*
Y0286083D01*
X0242724Y0288083*
X0242224*
X0241724Y0287583*
Y0286583*
X0242224Y0286083*
X0241724Y0291082D02*
X0242224Y0290082D01*
X0243224Y0289082*
X0244223*
X0244723Y0289582*
Y0290582*
X0244223Y0291082*
X0243724*
X0243224Y0290582*
Y0289082*
X0550666Y042868D02*
X0553665D01*
Y0427181*
X0553165Y0426681*
X0552165*
X0551665Y0427181*
Y042868*
X0553165Y0425681D02*
X0553665Y0425181D01*
Y0424182*
X0553165Y0423682*
X0552665*
X0552165Y0424182*
Y0424682*
Y0424182*
X0551665Y0423682*
X0551166*
X0550666Y0424182*
Y0425181*
X0551166Y0425681*
X038011Y0065476D02*
Y0062977D01*
X0380609Y0062477*
X0381609*
X0382109Y0062977*
Y0065476*
X0383108Y0062477D02*
X0384108D01*
X0383608*
Y0065476*
X0383108Y0064976*
X0385608D02*
X0386107Y0065476D01*
X0387107*
X0387607Y0064976*
Y0062977*
X0387107Y0062477*
X0386107*
X0385608Y0062977*
Y0064976*
X009894Y0258062D02*
X0095941D01*
Y0259562*
X0096441Y0260062*
X0097441*
X0097941Y0259562*
Y0258062*
Y0259062D02*
X009894Y0260062D01*
Y0261061D02*
Y0262061D01*
Y0261561*
X0095941*
X0096441Y0261061*
X009894Y026506D02*
X0095941D01*
X0097441Y0263561*
Y026556*
X0346645Y0273153D02*
Y0270654D01*
X0347145Y0270154*
X0348144*
X0348644Y0270654*
Y0273153*
X0349644Y0270154D02*
X0350644D01*
X0350144*
Y0273153*
X0349644Y0272653*
X0353643Y0270154D02*
Y0273153D01*
X0352143Y0271654*
X0354142*
X0316133Y0294807D02*
Y0292307D01*
X0316633Y0291808*
X0317633*
X0318132Y0292307*
Y0294807*
X0319132Y0291808D02*
X0320132D01*
X0319632*
Y0294807*
X0319132Y0294307*
X0321631D02*
X0322131Y0294807D01*
X0323131*
X0323631Y0294307*
Y0293807*
X0323131Y0293307*
X0322631*
X0323131*
X0323631Y0292807*
Y0292307*
X0323131Y0291808*
X0322131*
X0321631Y0292307*
X0109851Y0084327D02*
Y0086826D01*
X0109351Y0087326*
X0108352*
X0107852Y0086826*
Y0084327*
X0106852Y0087326D02*
X0105852D01*
X0106352*
Y0084327*
X0106852Y0084827*
X0102354Y0087326D02*
X0104353D01*
X0102354Y0085327*
Y0084827*
X0102853Y0084327*
X0103853*
X0104353Y0084827*
X0110924Y0209177D02*
Y0206678D01*
X0111424Y0206178*
X0112424*
X0112924Y0206678*
Y0209177*
X0113923Y0206178D02*
X0114923D01*
X0114423*
Y0209177*
X0113923Y0208677*
X0116422Y0206178D02*
X0117422D01*
X0116922*
Y0209177*
X0116422Y0208677*
X0111674Y0139295D02*
Y0136796D01*
X0112174Y0136296*
X0113174*
X0113673Y0136796*
Y0139295*
X0114673Y0138795D02*
X0115173Y0139295D01*
X0116173*
X0116672Y0138795*
Y0138295*
X0116173Y0137795*
X0116672Y0137295*
Y0136796*
X0116173Y0136296*
X0115173*
X0114673Y0136796*
Y0137295*
X0115173Y0137795*
X0114673Y0138295*
Y0138795*
X0115173Y0137795D02*
X0116173D01*
X0111674Y0262326D02*
Y0259827D01*
X0112174Y0259327*
X0113174*
X0113673Y0259827*
Y0262326*
X0116672D02*
X0115673Y0261826D01*
X0114673Y0260827*
Y0259827*
X0115173Y0259327*
X0116173*
X0116672Y0259827*
Y0260327*
X0116173Y0260827*
X0114673*
X0476831Y0297759D02*
Y029526D01*
X0477331Y029476*
X0478331*
X0478831Y029526*
Y0297759*
X048133Y029476D02*
Y0297759D01*
X0479831Y029626*
X048183*
X0547698Y0298744D02*
Y0296244D01*
X0548198Y0295745*
X0549197*
X0549697Y0296244*
Y0298744*
X0550697Y0298244D02*
X0551196Y0298744D01*
X0552196*
X0552696Y0298244*
Y0297744*
X0552196Y0297244*
X0551696*
X0552196*
X0552696Y0296744*
Y0296244*
X0552196Y0295745*
X0551196*
X0550697Y0296244*
X009894Y0100332D02*
X0095941D01*
Y0101831*
X0096441Y0102331*
X0097441*
X0097941Y0101831*
Y0100332*
Y0101332D02*
X009894Y0102331D01*
Y010533D02*
Y0103331D01*
X0096941Y010533*
X0096441*
X0095941Y0104831*
Y0103831*
X0096441Y0103331*
X0095941Y0108329D02*
Y010633D01*
X0097441*
X0096941Y010733*
Y010783*
X0097441Y0108329*
X0098441*
X009894Y010783*
Y010683*
X0098441Y010633*
X009894Y0205897D02*
X0095941D01*
Y0207396*
X0096441Y0207896*
X0097441*
X0097941Y0207396*
Y0205897*
Y0206897D02*
X009894Y0207896D01*
Y0208896D02*
Y0209896D01*
Y0209396*
X0095941*
X0096441Y0208896*
X0095941Y0211395D02*
Y0213394D01*
X0096441*
X0098441Y0211395*
X009894*
X049461Y028759D02*
X0491611D01*
Y0289089*
X0492111Y0289589*
X049311*
X049361Y0289089*
Y028759*
Y028859D02*
X049461Y0289589D01*
Y0290589D02*
Y0291588D01*
Y0291089*
X0491611*
X0492111Y0290589*
Y0293088D02*
X0491611Y0293588D01*
Y0294587*
X0492111Y0295087*
X049261*
X049311Y0294587*
Y0294088*
Y0294587*
X049361Y0295087*
X049411*
X049461Y0294587*
Y0293588*
X049411Y0293088*
X0457208Y027381D02*
X0454209D01*
Y027531*
X0454709Y027581*
X0455709*
X0456209Y027531*
Y027381*
Y027481D02*
X0457208Y027581D01*
Y0276809D02*
Y0277809D01*
Y0277309*
X0454209*
X0454709Y0276809*
X0457208Y0281308D02*
Y0279309D01*
X0455209Y0281308*
X0454709*
X0454209Y0280808*
Y0279808*
X0454709Y0279309*
X0505609Y027606D02*
Y0279059D01*
X0507109*
X0507609Y0278559*
Y0277559*
X0507109Y0277059*
X0505609*
X0506609D02*
X0507609Y027606D01*
X0508608D02*
X0509608D01*
X0509108*
Y0279059*
X0508608Y0278559*
X0511107Y027606D02*
X0512107D01*
X0511607*
Y0279059*
X0511107Y0278559*
X0507078Y0284918D02*
Y0287917D01*
X0508577*
X0509077Y0287417*
Y0286417*
X0508577Y0285917*
X0507078*
X0508078D02*
X0509077Y0284918D01*
X0510077D02*
X0511077D01*
X0510577*
Y0287917*
X0510077Y0287417*
X0512576D02*
X0513076Y0287917D01*
X0514076*
X0514576Y0287417*
Y0285418*
X0514076Y0284918*
X0513076*
X0512576Y0285418*
Y0287417*
X0336599Y028245D02*
X0336099Y028195D01*
Y028095*
X0336599Y028045*
X0338598*
X0339098Y028095*
Y028195*
X0338598Y028245*
X0336599Y0283449D02*
X0336099Y0283949D01*
Y0284949*
X0336599Y0285449*
X0337099*
X0337598Y0284949*
Y0284449*
Y0284949*
X0338098Y0285449*
X0338598*
X0339098Y0284949*
Y0283949*
X0338598Y0283449*
X0336599Y0286448D02*
X0336099Y0286948D01*
Y0287948*
X0336599Y0288447*
X0337099*
X0337598Y0287948*
Y0287448*
Y0287948*
X0338098Y0288447*
X0338598*
X0339098Y0287948*
Y0286948*
X0338598Y0286448*
X0307056Y0270685D02*
X0306556Y0271185D01*
X0305556*
X0305056Y0270685*
Y0268685*
X0305556Y0268185*
X0306556*
X0307056Y0268685*
X0308055Y0270685D02*
X0308555Y0271185D01*
X0309555*
X0310055Y0270685*
Y0270185*
X0309555Y0269685*
X0309055*
X0309555*
X0310055Y0269185*
Y0268685*
X0309555Y0268185*
X0308555*
X0308055Y0268685*
X0313054Y0268185D02*
X0311054D01*
X0313054Y0270185*
Y0270685*
X0312554Y0271185*
X0311554*
X0311054Y0270685*
X0365142Y0279406D02*
X0364642Y0278906D01*
Y0277906*
X0365142Y0277407*
X0367141*
X0367641Y0277906*
Y0278906*
X0367141Y0279406*
X0365142Y0280406D02*
X0364642Y0280906D01*
Y0281905*
X0365142Y0282405*
X0365642*
X0366142Y0281905*
Y0281405*
Y0281905*
X0366642Y0282405*
X0367141*
X0367641Y0281905*
Y0280906*
X0367141Y0280406*
X0367641Y0283405D02*
Y0284404D01*
Y0283905*
X0364642*
X0365142Y0283405*
X0339536Y0296275D02*
X0339036Y0296775D01*
X0338037*
X0337537Y0296275*
Y0294276*
X0338037Y0293776*
X0339036*
X0339536Y0294276*
X0340536Y0296275D02*
X0341036Y0296775D01*
X0342035*
X0342535Y0296275*
Y0295775*
X0342035Y0295276*
X0341535*
X0342035*
X0342535Y0294776*
Y0294276*
X0342035Y0293776*
X0341036*
X0340536Y0294276*
X0343535Y0296275D02*
X0344035Y0296775D01*
X0345034*
X0345534Y0296275*
Y0294276*
X0345034Y0293776*
X0344035*
X0343535Y0294276*
Y0296275*
X0118079Y0162417D02*
X011758Y0162917D01*
X011658*
X011608Y0162417*
Y0160418*
X011658Y0159918*
X011758*
X0118079Y0160418*
X0121078Y0159918D02*
X0119079D01*
X0121078Y0161917*
Y0162417*
X0120579Y0162917*
X0119579*
X0119079Y0162417*
X0122078Y0160418D02*
X0122578Y0159918D01*
X0123578*
X0124077Y0160418*
Y0162417*
X0123578Y0162917*
X0122578*
X0122078Y0162417*
Y0161917*
X0122578Y0161417*
X0124077*
X0122865Y0109433D02*
X0123365Y0108933D01*
X0124365*
X0124865Y0109433*
Y0111433*
X0124365Y0111933*
X0123365*
X0122865Y0111433*
X0119867Y0111933D02*
X0121866D01*
X0119867Y0109933*
Y0109433*
X0120366Y0108933*
X0121366*
X0121866Y0109433*
X0118867D02*
X0118367Y0108933D01*
X0117367*
X0116867Y0109433*
Y0109933*
X0117367Y0110433*
X0116867Y0110933*
Y0111433*
X0117367Y0111933*
X0118367*
X0118867Y0111433*
Y0110933*
X0118367Y0110433*
X0118867Y0109933*
Y0109433*
X0118367Y0110433D02*
X0117367D01*
X0096339Y0184711D02*
X0095839Y0185211D01*
X009484*
X009434Y0184711*
Y0182712*
X009484Y0182212*
X0095839*
X0096339Y0182712*
X0099338Y0182212D02*
X0097339D01*
X0099338Y0184211*
Y0184711*
X0098838Y0185211*
X0097839*
X0097339Y0184711*
X0100338Y0185211D02*
X0102337D01*
Y0184711*
X0100338Y0182712*
Y0182212*
X0096229Y0238204D02*
X0095729Y0238704D01*
X009473*
X009423Y0238204*
Y0236205*
X009473Y0235705*
X0095729*
X0096229Y0236205*
X0099228Y0235705D02*
X0097229D01*
X0099228Y0237705*
Y0238204*
X0098728Y0238704*
X0097729*
X0097229Y0238204*
X0102227Y0238704D02*
X0101227Y0238204D01*
X0100228Y0237205*
Y0236205*
X0100727Y0235705*
X0101727*
X0102227Y0236205*
Y0236705*
X0101727Y0237205*
X0100228*
X0499Y0272607D02*
X04985Y0272107D01*
Y0271107*
X0499Y0270608*
X0501*
X05015Y0271107*
Y0272107*
X0501Y0272607*
X05015Y0275606D02*
Y0273607D01*
X04995Y0275606*
X0499*
X04985Y0275106*
Y0274107*
X0499Y0273607*
X05015Y0278105D02*
X04985D01*
X05Y0276606*
Y0278605*
X0508827Y0293322D02*
X0508328Y0293822D01*
X0507328*
X0506828Y0293322*
Y0291323*
X0507328Y0290823*
X0508328*
X0508827Y0291323*
X0511827Y0290823D02*
X0509827D01*
X0511827Y0292823*
Y0293322*
X0511327Y0293822*
X0510327*
X0509827Y0293322*
X0512826D02*
X0513326Y0293822D01*
X0514326*
X0514825Y0293322*
Y0292823*
X0514326Y0292323*
X0513826*
X0514326*
X0514825Y0291823*
Y0291323*
X0514326Y0290823*
X0513326*
X0512826Y0291323*
X0003937Y0223425D02*
Y0225425D01*
X0004937Y0226424*
X0005936Y0225425*
Y0223425*
Y0224925*
X0003937*
X0006936Y0223425D02*
Y0226424D01*
X0008935Y0223425*
Y0226424*
X0009935Y0223425D02*
X0010935D01*
X0010435*
Y0226424*
X0009935Y0225924*
X0003937Y017126D02*
Y0173259D01*
X0004937Y0174259*
X0005936Y0173259*
Y017126*
Y0172759*
X0003937*
X0006936Y017126D02*
Y0174259D01*
X0008935Y017126*
Y0174259*
X0011934Y017126D02*
X0009935D01*
X0011934Y0173259*
Y0173759*
X0011435Y0174259*
X0010435*
X0009935Y0173759*
X0003937Y0119095D02*
Y0121094D01*
X0004937Y0122093*
X0005936Y0121094*
Y0119095*
Y0120594*
X0003937*
X0006936Y0119095D02*
Y0122093D01*
X0008935Y0119095*
Y0122093*
X0009935Y0121594D02*
X0010435Y0122093D01*
X0011435*
X0011934Y0121594*
Y0121094*
X0011435Y0120594*
X0010935*
X0011435*
X0011934Y0120094*
Y0119594*
X0011435Y0119095*
X0010435*
X0009935Y0119594*
X0003937Y0066929D02*
Y0068928D01*
X0004937Y0069928*
X0005936Y0068928*
Y0066929*
Y0068429*
X0003937*
X0006936Y0066929D02*
Y0069928D01*
X0008935Y0066929*
Y0069928*
X0011435Y0066929D02*
Y0069928D01*
X0009935Y0068429*
X0011934*
X0062477Y0083881D02*
Y0082881D01*
Y0083381*
X0064976*
X0065476Y0082881*
Y0082381*
X0064976Y0081881*
X0065476Y008488D02*
Y008588D01*
Y008538*
X0062477*
X0062977Y008488*
Y0087379D02*
X0062477Y0087879D01*
Y0088879*
X0062977Y0089379*
X0064976*
X0065476Y0088879*
Y0087879*
X0064976Y0087379*
X0062977*
X0062477Y0136311D02*
Y0135311D01*
Y0135811*
X0064976*
X0065476Y0135311*
Y0134812*
X0064976Y0134312*
Y0137311D02*
X0065476Y0137811D01*
Y013881*
X0064976Y013931*
X0062977*
X0062477Y013881*
Y0137811*
X0062977Y0137311*
X0063477*
X0063976Y0137811*
Y013931*
X0062477Y0241626D02*
Y0240627D01*
Y0241126*
X0064976*
X0065476Y0240627*
Y0240127*
X0064976Y0239627*
X0062477Y0244625D02*
X0062977Y0243625D01*
X0063976Y0242626*
X0064976*
X0065476Y0243126*
Y0244125*
X0064976Y0244625*
X0064476*
X0063976Y0244125*
Y0242626*
X0062477Y0188477D02*
Y0187477D01*
Y0187977*
X0064976*
X0065476Y0187477*
Y0186977*
X0064976Y0186477*
X0062477Y0191476D02*
Y0189476D01*
X0063976*
X0063477Y0190476*
Y0190976*
X0063976Y0191476*
X0064976*
X0065476Y0190976*
Y0189976*
X0064976Y0189476*
X0282419Y0268185D02*
Y0271185D01*
X0283918*
X0284418Y0270685*
Y0269685*
X0283918Y0269185*
X0282419*
X0283418D02*
X0284418Y0268185D01*
X0285418Y0270685D02*
X0285917Y0271185D01*
X0286917*
X0287417Y0270685*
Y0270185*
X0286917Y0269685*
X0286417*
X0286917*
X0287417Y0269185*
Y0268685*
X0286917Y0268185*
X0285917*
X0285418Y0268685*
X0288417Y0271185D02*
X0290416D01*
Y0270685*
X0288417Y0268685*
Y0268185*
X0291792Y0293822D02*
Y0291323D01*
X0292292Y0290823*
X0293292*
X0293792Y0291323*
Y0293822*
X0294791D02*
X0296791D01*
Y0293322*
X0294791Y0291323*
Y0290823*
X0283434Y0293322D02*
X0282934Y0293822D01*
X0281934*
X0281434Y0293322*
Y0291323*
X0281934Y0290823*
X0282934*
X0283434Y0291323*
X0286433Y0290823D02*
X0284433D01*
X0286433Y0292823*
Y0293322*
X0285933Y0293822*
X0284933*
X0284433Y0293322*
X0289432Y0293822D02*
X0287432D01*
Y0292323*
X0288432Y0292823*
X0288932*
X0289432Y0292323*
Y0291323*
X0288932Y0290823*
X0287932*
X0287432Y0291323*
X005898Y0403731D02*
X0055981D01*
Y0405231*
X0056481Y0405731*
X005748*
X005798Y0405231*
Y0403731*
Y0404731D02*
X005898Y0405731D01*
Y0406731D02*
Y040773D01*
Y040723*
X0055981*
X0056481Y0406731*
X0055981Y0411229D02*
X0056481Y0410229D01*
X005748Y040923*
X005848*
X005898Y040973*
Y0410729*
X005848Y0411229*
X005798*
X005748Y0410729*
Y040923*
X009894Y0132078D02*
X0095941D01*
Y0133578*
X0096441Y0134077*
X0097441*
X0097941Y0133578*
Y0132078*
Y0133078D02*
X009894Y0134077D01*
Y0135077D02*
Y0136077D01*
Y0135577*
X0095941*
X0096441Y0135077*
X0095941Y0139576D02*
Y0137576D01*
X0097441*
X0096941Y0138576*
Y0139076*
X0097441Y0139576*
X0098441*
X009894Y0139076*
Y0138076*
X0098441Y0137576*
X0613484Y0252559D02*
X0610485D01*
Y0254059*
X0610985Y0254558*
X0611985*
X0612485Y0254059*
Y0252559*
Y0253559D02*
X0613484Y0254558D01*
X0610485Y0257557D02*
Y0255558D01*
X0611985*
X0611485Y0256558*
Y0257058*
X0611985Y0257557*
X0612984*
X0613484Y0257058*
Y0256058*
X0612984Y0255558*
X0251969Y0375046D02*
Y0372547D01*
X0252468Y0372047*
X0253468*
X0253968Y0372547*
Y0375046*
X0254967Y0372547D02*
X0255467Y0372047D01*
X0256467*
X0256967Y0372547*
Y0374546*
X0256467Y0375046*
X0255467*
X0254967Y0374546*
Y0374047*
X0255467Y0373547*
X0256967*
X0143701Y0424259D02*
Y042176D01*
X0144201Y042126*
X01452*
X01457Y042176*
Y0424259*
X0148699D02*
X01467D01*
Y0422759*
X0147699Y0423259*
X0148199*
X0148699Y0422759*
Y042176*
X0148199Y042126*
X01472*
X01467Y042176*
X0601335Y0226056D02*
Y0223557D01*
X0601835Y0223057*
X0602835*
X0603335Y0223557*
Y0226056*
X0606334Y0223057D02*
X0604334D01*
X0606334Y0225056*
Y0225556*
X0605834Y0226056*
X0604834*
X0604334Y0225556*
X0656102Y0210676D02*
Y0208177D01*
X0656602Y0207677*
X0657602*
X0658102Y0208177*
Y0210676*
X0659101Y0207677D02*
X0660101D01*
X0659601*
Y0210676*
X0659101Y0210176*
X0119685Y0402756D02*
X0116686D01*
Y0404255*
X0117186Y0404755*
X0118185*
X0118685Y0404255*
Y0402756*
Y0403756D02*
X0119685Y0404755D01*
X0117186Y0405755D02*
X0116686Y0406255D01*
Y0407255*
X0117186Y0407754*
X0117686*
X0118185Y0407255*
Y0406755*
Y0407255*
X0118685Y0407754*
X0119185*
X0119685Y0407255*
Y0406255*
X0119185Y0405755*
X0117186Y0408754D02*
X0116686Y0409254D01*
Y0410253*
X0117186Y0410753*
X0119185*
X0119685Y0410253*
Y0409254*
X0119185Y0408754*
X0117186*
X0099606Y040315D02*
X0096607D01*
Y0404649*
X0097107Y0405149*
X0098107*
X0098607Y0404649*
Y040315*
Y0404149D02*
X0099606Y0405149D01*
Y0408148D02*
Y0406149D01*
X0097607Y0408148*
X0097107*
X0096607Y0407648*
Y0406648*
X0097107Y0406149*
X0099107Y0409148D02*
X0099606Y0409648D01*
Y0410647*
X0099107Y0411147*
X0097107*
X0096607Y0410647*
Y0409648*
X0097107Y0409148*
X0097607*
X0098107Y0409648*
Y0411147*
X0079528Y040315D02*
X0076529D01*
Y0404649*
X0077028Y0405149*
X0078028*
X0078528Y0404649*
Y040315*
Y0404149D02*
X0079528Y0405149D01*
Y0408148D02*
Y0406149D01*
X0077528Y0408148*
X0077028*
X0076529Y0407648*
Y0406648*
X0077028Y0406149*
Y0409148D02*
X0076529Y0409648D01*
Y0410647*
X0077028Y0411147*
X0077528*
X0078028Y0410647*
X0078528Y0411147*
X0079028*
X0079528Y0410647*
Y0409648*
X0079028Y0409148*
X0078528*
X0078028Y0409648*
X0077528Y0409148*
X0077028*
X0078028Y0409648D02*
Y0410647D01*
X0301661Y0053736D02*
X0298662D01*
Y0055235*
X0299162Y0055735*
X0300162*
X0300661Y0055235*
Y0053736*
Y0054735D02*
X0301661Y0055735D01*
Y0058734D02*
Y0056735D01*
X0299662Y0058734*
X0299162*
X0298662Y0058234*
Y0057235*
X0299162Y0056735*
X0301661Y0061233D02*
X0298662D01*
X0300162Y0059734*
Y0061733*
X0246843Y0054036D02*
X0243844D01*
Y0055535*
X0244344Y0056035*
X0245343*
X0245843Y0055535*
Y0054036*
Y0055036D02*
X0246843Y0056035D01*
Y0059034D02*
Y0057035D01*
X0244844Y0059034*
X0244344*
X0243844Y0058534*
Y0057535*
X0244344Y0057035*
Y0060034D02*
X0243844Y0060534D01*
Y0061533*
X0244344Y0062033*
X0244844*
X0245343Y0061533*
Y0061033*
Y0061533*
X0245843Y0062033*
X0246343*
X0246843Y0061533*
Y0060534*
X0246343Y0060034*
X0137795Y0155512D02*
Y0158511D01*
X0139295*
X0139795Y0158011*
Y0157011*
X0139295Y0156511*
X0137795*
X0138795D02*
X0139795Y0155512D01*
X0142794D02*
X0140794D01*
X0142794Y0157511*
Y0158011*
X0142294Y0158511*
X0141294*
X0140794Y0158011*
X0145793Y0155512D02*
X0143793D01*
X0145793Y0157511*
Y0158011*
X0145293Y0158511*
X0144293*
X0143793Y0158011*
X0195866Y0370079D02*
X0192867D01*
Y0371578*
X0193367Y0372078*
X0194367*
X0194867Y0371578*
Y0370079*
Y0371078D02*
X0195866Y0372078D01*
Y0375077D02*
Y0373078D01*
X0193867Y0375077*
X0193367*
X0192867Y0374577*
Y0373578*
X0193367Y0373078*
X0195866Y0376077D02*
Y0377077D01*
Y0376577*
X0192867*
X0193367Y0376077*
X0155512Y0370079D02*
X0152513D01*
Y0371578*
X0153013Y0372078*
X0154012*
X0154512Y0371578*
Y0370079*
Y0371078D02*
X0155512Y0372078D01*
Y0375077D02*
Y0373078D01*
X0153513Y0375077*
X0153013*
X0152513Y0374577*
Y0373578*
X0153013Y0373078*
Y0376077D02*
X0152513Y0376577D01*
Y0377576*
X0153013Y0378076*
X0155012*
X0155512Y0377576*
Y0376577*
X0155012Y0376077*
X0153013*
X0150591Y0370079D02*
X0147591D01*
Y0371578*
X0148091Y0372078*
X0149091*
X0149591Y0371578*
Y0370079*
Y0371078D02*
X0150591Y0372078D01*
Y0373078D02*
Y0374077D01*
Y0373578*
X0147591*
X0148091Y0373078*
X0150091Y0375577D02*
X0150591Y0376077D01*
Y0377077*
X0150091Y0377576*
X0148091*
X0147591Y0377077*
Y0376077*
X0148091Y0375577*
X0148591*
X0149091Y0376077*
Y0377576*
X0145669Y0370079D02*
X014267D01*
Y0371578*
X014317Y0372078*
X014417*
X014467Y0371578*
Y0370079*
Y0371078D02*
X0145669Y0372078D01*
Y0373078D02*
Y0374077D01*
Y0373578*
X014267*
X014317Y0373078*
Y0375577D02*
X014267Y0376077D01*
Y0377077*
X014317Y0377576*
X014367*
X014417Y0377077*
X014467Y0377576*
X0145169*
X0145669Y0377077*
Y0376077*
X0145169Y0375577*
X014467*
X014417Y0376077*
X014367Y0375577*
X014317*
X014417Y0376077D02*
Y0377077D01*
X0601583Y0245776D02*
X0598584D01*
Y0247275*
X0599084Y0247775*
X0600083*
X0600583Y0247275*
Y0245776*
Y0246775D02*
X0601583Y0247775D01*
X0601083Y0248775D02*
X0601583Y0249274D01*
Y0250274*
X0601083Y0250774*
X0599084*
X0598584Y0250274*
Y0249274*
X0599084Y0248775*
X0599583*
X0600083Y0249274*
Y0250774*
X0701181Y0196457D02*
X0698182D01*
Y0197956*
X0698682Y0198456*
X0699682*
X0700181Y0197956*
Y0196457*
Y0197456D02*
X0701181Y0198456D01*
X0698682Y0199456D02*
X0698182Y0199956D01*
Y0200955*
X0698682Y0201455*
X0699182*
X0699682Y0200955*
X0700181Y0201455*
X0700681*
X0701181Y0200955*
Y0199956*
X0700681Y0199456*
X0700181*
X0699682Y0199956*
X0699182Y0199456*
X0698682*
X0699682Y0199956D02*
Y0200955D01*
X0618181Y0245051D02*
Y024805D01*
X0619681*
X0620181Y024755*
Y0246551*
X0619681Y0246051*
X0618181*
X0619181D02*
X0620181Y0245051D01*
X062118Y024805D02*
X0623179D01*
Y024755*
X062118Y0245551*
Y0245051*
X0663Y0180992D02*
Y0183991D01*
X06645*
X0664999Y0183491*
Y0182492*
X06645Y0181992*
X0663*
X0664D02*
X0664999Y0180992D01*
X0667998Y0183991D02*
X0666999Y0183491D01*
X0665999Y0182492*
Y0181492*
X0666499Y0180992*
X0667498*
X0667998Y0181492*
Y0181992*
X0667498Y0182492*
X0665999*
X0684547Y0175D02*
Y0177999D01*
X0686047*
X0686547Y0177499*
Y0176499*
X0686047Y0176*
X0684547*
X0685547D02*
X0686547Y0175D01*
X0689046D02*
Y0177999D01*
X0687546Y0176499*
X0689546*
X0624803Y0204331D02*
X0621804D01*
Y020583*
X0622304Y020633*
X0623304*
X0623804Y020583*
Y0204331*
Y020533D02*
X0624803Y020633D01*
X0622304Y020733D02*
X0621804Y020783D01*
Y0208829*
X0622304Y0209329*
X0622804*
X0623304Y0208829*
Y0208329*
Y0208829*
X0623804Y0209329*
X0624303*
X0624803Y0208829*
Y020783*
X0624303Y020733*
X0676673Y0217421D02*
X0673674D01*
Y0218921*
X0674174Y0219421*
X0675174*
X0675673Y0218921*
Y0217421*
Y0218421D02*
X0676673Y0219421D01*
Y022242D02*
Y022042D01*
X0674674Y022242*
X0674174*
X0673674Y022192*
Y022092*
X0674174Y022042*
X0614173Y0292913D02*
X0611174D01*
Y0294413*
X0611674Y0294913*
X0612674*
X0613173Y0294413*
Y0292913*
Y0293913D02*
X0614173Y0294913D01*
Y0295912D02*
Y0296912D01*
Y0296412*
X0611174*
X0611674Y0295912*
X0155684Y0261806D02*
Y0264805D01*
X0157184*
X0157684Y0264305*
Y0263306*
X0157184Y0262806*
X0155684*
X0158683Y0261806D02*
X0159683D01*
X0159183*
Y0264805*
X0158683Y0264305*
X0686635Y0293956D02*
Y0290957D01*
X0688635*
X0691634D02*
X0689635D01*
X0691634Y0292956*
Y0293456*
X0691134Y0293956*
X0690134*
X0689635Y0293456*
X0597385Y0189956D02*
Y0186957D01*
X0599385*
X0600384D02*
X0601384D01*
X0600884*
Y0189956*
X0600384Y0189456*
X0191883Y0072865D02*
Y0070866D01*
X0193382*
Y0071866*
Y0070866*
X0194882*
Y0073865D02*
Y0074865D01*
Y0074365*
X0191883*
X0192383Y0073865*
X0116235Y0416783D02*
X0119234D01*
Y0418283*
X0118734Y0418783*
X0116734*
X0116235Y0418283*
Y0416783*
X0119234Y0419782D02*
Y0420782D01*
Y0420282*
X0116235*
X0116734Y0419782*
X0119234Y0423781D02*
X0116235D01*
X0117734Y0422281*
Y0424281*
X0096034Y0416483D02*
X0099033D01*
Y0417983*
X0098534Y0418482*
X0096534*
X0096034Y0417983*
Y0416483*
X0099033Y0419482D02*
Y0420482D01*
Y0419982*
X0096034*
X0096534Y0419482*
Y0421981D02*
X0096034Y0422481D01*
Y0423481*
X0096534Y0423981*
X0097034*
X0097534Y0423481*
Y0422981*
Y0423481*
X0098034Y0423981*
X0098534*
X0099033Y0423481*
Y0422481*
X0098534Y0421981*
X0076434Y0416883D02*
X0079434D01*
Y0418383*
X0078934Y0418883*
X0076934*
X0076434Y0418383*
Y0416883*
X0079434Y0419882D02*
Y0420882D01*
Y0420382*
X0076434*
X0076934Y0419882*
X0079434Y0424381D02*
Y0422381D01*
X0077434Y0424381*
X0076934*
X0076434Y0423881*
Y0422881*
X0076934Y0422381*
X0056134Y0417833D02*
X0059133D01*
Y0419332*
X0058634Y0419832*
X0056634*
X0056134Y0419332*
Y0417833*
X0059133Y0420832D02*
Y0421832D01*
Y0421332*
X0056134*
X0056634Y0420832*
X0059133Y0423331D02*
Y0424331D01*
Y0423831*
X0056134*
X0056634Y0423331*
X0203248Y0353393D02*
Y0350394D01*
X0204748*
X0205247Y0350893*
Y0352893*
X0204748Y0353393*
X0203248*
X0206247Y0352893D02*
X0206747Y0353393D01*
X0207747*
X0208246Y0352893*
Y0352393*
X0207747Y0351893*
X0208246Y0351393*
Y0350893*
X0207747Y0350394*
X0206747*
X0206247Y0350893*
Y0351393*
X0206747Y0351893*
X0206247Y0352393*
Y0352893*
X0206747Y0351893D02*
X0207747D01*
X0185531Y0353393D02*
Y0350394D01*
X0187031*
X0187531Y0350893*
Y0352893*
X0187031Y0353393*
X0185531*
X0188531D02*
X019053D01*
Y0352893*
X0188531Y0350893*
Y0350394*
X0167323Y0353393D02*
Y0350394D01*
X0168822*
X0169322Y0350893*
Y0352893*
X0168822Y0353393*
X0167323*
X0172321D02*
X0171322Y0352893D01*
X0170322Y0351893*
Y0350893*
X0170822Y0350394*
X0171821*
X0172321Y0350893*
Y0351393*
X0171821Y0351893*
X0170322*
X0148622Y0353393D02*
Y0350394D01*
X0150122*
X0150621Y0350893*
Y0352893*
X0150122Y0353393*
X0148622*
X015362D02*
X0151621D01*
Y0351893*
X0152621Y0352393*
X0153121*
X015362Y0351893*
Y0350893*
X0153121Y0350394*
X0152121*
X0151621Y0350893*
X0617473Y0292913D02*
X0620472D01*
Y0294413*
X0619973Y0294913*
X0617973*
X0617473Y0294413*
Y0292913*
X0620472Y0297412D02*
X0617473D01*
X0618973Y0295912*
Y0297912*
X0184009Y0070472D02*
X0187008D01*
Y0071972*
X0186508Y0072472*
X0184509*
X0184009Y0071972*
Y0070472*
X0184509Y0073471D02*
X0184009Y0073971D01*
Y0074971*
X0184509Y0075471*
X0185009*
X0185508Y0074971*
Y0074471*
Y0074971*
X0186008Y0075471*
X0186508*
X0187008Y0074971*
Y0073971*
X0186508Y0073471*
X0341862Y0066672D02*
X0341362Y0067172D01*
X0340362*
X0339862Y0066672*
Y0064673*
X0340362Y0064173*
X0341362*
X0341862Y0064673*
X0344861Y0067172D02*
X0343861Y0066672D01*
X0342861Y0065673*
Y0064673*
X0343361Y0064173*
X0344361*
X0344861Y0064673*
Y0065173*
X0344361Y0065673*
X0342861*
X034586Y0066672D02*
X034636Y0067172D01*
X034736*
X034786Y0066672*
Y0066173*
X034736Y0065673*
X034686*
X034736*
X034786Y0065173*
Y0064673*
X034736Y0064173*
X034636*
X034586Y0064673*
X0341862Y0074153D02*
X0341362Y0074653D01*
X0340362*
X0339862Y0074153*
Y0072153*
X0340362Y0071653*
X0341362*
X0341862Y0072153*
X0344861Y0074653D02*
X0343861Y0074153D01*
X0342861Y0073153*
Y0072153*
X0343361Y0071653*
X0344361*
X0344861Y0072153*
Y0072653*
X0344361Y0073153*
X0342861*
X034786Y0071653D02*
X034586D01*
X034786Y0073653*
Y0074153*
X034736Y0074653*
X034636*
X034586Y0074153*
X028195Y0314007D02*
X028145Y0313507D01*
Y0312508*
X028195Y0312008*
X0283949*
X0284449Y0312508*
Y0313507*
X0283949Y0314007*
X028145Y0317006D02*
X028195Y0316007D01*
X0282949Y0315007*
X0283949*
X0284449Y0315507*
Y0316506*
X0283949Y0317006*
X0283449*
X0282949Y0316506*
Y0315007*
X0284449Y0318006D02*
Y0319006D01*
Y0318506*
X028145*
X028195Y0318006*
X0277028Y0314007D02*
X0276529Y0313507D01*
Y0312508*
X0277028Y0312008*
X0279028*
X0279528Y0312508*
Y0313507*
X0279028Y0314007*
X0276529Y0317006D02*
X0277028Y0316007D01*
X0278028Y0315007*
X0279028*
X0279528Y0315507*
Y0316506*
X0279028Y0317006*
X0278528*
X0278028Y0316506*
Y0315007*
X0277028Y0318006D02*
X0276529Y0318506D01*
Y0319506*
X0277028Y0320005*
X0279028*
X0279528Y0319506*
Y0318506*
X0279028Y0318006*
X0277028*
X0288839Y0320897D02*
X028834Y0320397D01*
Y0319397*
X0288839Y0318898*
X0290839*
X0291339Y0319397*
Y0320397*
X0290839Y0320897*
X028834Y0323896D02*
Y0321897D01*
X0289839*
X0289339Y0322896*
Y0323396*
X0289839Y0323896*
X0290839*
X0291339Y0323396*
Y0322396*
X0290839Y0321897*
Y0324896D02*
X0291339Y0325395D01*
Y0326395*
X0290839Y0326895*
X0288839*
X028834Y0326395*
Y0325395*
X0288839Y0324896*
X0289339*
X0289839Y0325395*
Y0326895*
X0295729Y0320897D02*
X0295229Y0320397D01*
Y0319397*
X0295729Y0318898*
X0297728*
X0298228Y0319397*
Y0320397*
X0297728Y0320897*
X0295229Y0323896D02*
Y0321897D01*
X0296729*
X0296229Y0322896*
Y0323396*
X0296729Y0323896*
X0297728*
X0298228Y0323396*
Y0322396*
X0297728Y0321897*
X0295729Y0324896D02*
X0295229Y0325395D01*
Y0326395*
X0295729Y0326895*
X0296229*
X0296729Y0326395*
X0297229Y0326895*
X0297728*
X0298228Y0326395*
Y0325395*
X0297728Y0324896*
X0297229*
X0296729Y0325395*
X0296229Y0324896*
X0295729*
X0296729Y0325395D02*
Y0326395D01*
X0605178Y0243929D02*
X0604678Y0243429D01*
Y0242429*
X0605178Y0241929*
X0607177*
X0607677Y0242429*
Y0243429*
X0607177Y0243929*
X0607677Y0246927D02*
Y0244928D01*
X0605678Y0246927*
X0605178*
X0604678Y0246428*
Y0245428*
X0605178Y0244928*
X0607677Y0249926D02*
Y0247927D01*
X0605678Y0249926*
X0605178*
X0604678Y0249427*
Y0248427*
X0605178Y0247927*
X0597275Y0217853D02*
X0596775Y0218353D01*
X0595775*
X0595276Y0217853*
Y0215854*
X0595775Y0215354*
X0596775*
X0597275Y0215854*
X0600274Y0215354D02*
X0598275D01*
X0600274Y0217354*
Y0217853*
X0599774Y0218353*
X0598774*
X0598275Y0217853*
X0601274Y0215354D02*
X0602273D01*
X0601774*
Y0218353*
X0601274Y0217853*
X0692481Y0197865D02*
X0691981Y0197366D01*
Y0196366*
X0692481Y0195866*
X0694481*
X069498Y0196366*
Y0197366*
X0694481Y0197865*
X069498Y0200865D02*
Y0198865D01*
X0692981Y0200865*
X0692481*
X0691981Y0200365*
Y0199365*
X0692481Y0198865*
Y0201864D02*
X0691981Y0202364D01*
Y0203364*
X0692481Y0203864*
X0694481*
X069498Y0203364*
Y0202364*
X0694481Y0201864*
X0692481*
X0685365Y0216968D02*
X0684866Y0217467D01*
X0683866*
X0683366Y0216968*
Y0214968*
X0683866Y0214469*
X0684866*
X0685365Y0214968*
X0686365Y0214469D02*
X0687365D01*
X0686865*
Y0217467*
X0686365Y0216968*
X0688864Y0214968D02*
X0689364Y0214469D01*
X0690364*
X0690864Y0214968*
Y0216968*
X0690364Y0217467*
X0689364*
X0688864Y0216968*
Y0216468*
X0689364Y0215968*
X0690864*
X0674834Y0176909D02*
X0674334Y0177409D01*
X0673335*
X0672835Y0176909*
Y0174909*
X0673335Y0174409*
X0674334*
X0674834Y0174909*
X0675834Y0174409D02*
X0676833D01*
X0676334*
Y0177409*
X0675834Y0176909*
X0678333D02*
X0678833Y0177409D01*
X0679832*
X0680332Y0176909*
Y0176409*
X0679832Y0175909*
X0680332Y0175409*
Y0174909*
X0679832Y0174409*
X0678833*
X0678333Y0174909*
Y0175409*
X0678833Y0175909*
X0678333Y0176409*
Y0176909*
X0678833Y0175909D02*
X0679832D01*
X0674834Y0172184D02*
X0674334Y0172684D01*
X0673335*
X0672835Y0172184*
Y0170185*
X0673335Y0169685*
X0674334*
X0674834Y0170185*
X0675834Y0169685D02*
X0676833D01*
X0676334*
Y0172684*
X0675834Y0172184*
X0678333Y0172684D02*
X0680332D01*
Y0172184*
X0678333Y0170185*
Y0169685*
X0674834Y016746D02*
X0674334Y016796D01*
X0673335*
X0672835Y016746*
Y0165461*
X0673335Y0164961*
X0674334*
X0674834Y0165461*
X0675834Y0164961D02*
X0676833D01*
X0676334*
Y016796*
X0675834Y016746*
X0680332Y016796D02*
X0679332Y016746D01*
X0678333Y016646*
Y0165461*
X0678833Y0164961*
X0679832*
X0680332Y0165461*
Y016596*
X0679832Y016646*
X0678333*
X0674834Y0162342D02*
X0674334Y0162842D01*
X0673335*
X0672835Y0162342*
Y0160342*
X0673335Y0159843*
X0674334*
X0674834Y0160342*
X0675834Y0159843D02*
X0676833D01*
X0676334*
Y0162842*
X0675834Y0162342*
X0680332Y0162842D02*
X0678333D01*
Y0161342*
X0679332Y0161842*
X0679832*
X0680332Y0161342*
Y0160342*
X0679832Y0159843*
X0678833*
X0678333Y0160342*
X067626Y0149656D02*
X0675761Y0150156D01*
X0674761*
X0674261Y0149656*
Y0147657*
X0674761Y0147157*
X0675761*
X067626Y0147657*
X067726Y0147157D02*
X067826D01*
X067776*
Y0150156*
X067726Y0149656*
X0681259Y0147157D02*
Y0150156D01*
X0679759Y0148656*
X0681759*
X067616Y0142256D02*
X0675661Y0142756D01*
X0674661*
X0674161Y0142256*
Y0140257*
X0674661Y0139757*
X0675661*
X067616Y0140257*
X067716Y0139757D02*
X067816D01*
X067766*
Y0142756*
X067716Y0142256*
X0679659D02*
X0680159Y0142756D01*
X0681159*
X0681659Y0142256*
Y0141756*
X0681159Y0141256*
X0680659*
X0681159*
X0681659Y0140757*
Y0140257*
X0681159Y0139757*
X0680159*
X0679659Y0140257*
X0619716Y0270609D02*
X0619216Y0271109D01*
X0618216*
X0617717Y0270609*
Y026861*
X0618216Y026811*
X0619216*
X0619716Y026861*
X0620716Y026811D02*
X0621715D01*
X0621215*
Y0271109*
X0620716Y0270609*
X0625214Y026811D02*
X0623215D01*
X0625214Y027011*
Y0270609*
X0624714Y0271109*
X0623715*
X0623215Y0270609*
X062011Y0265885D02*
X061961Y0266385D01*
X061861*
X061811Y0265885*
Y0263886*
X061861Y0263386*
X061961*
X062011Y0263886*
X0621109Y0263386D02*
X0622109D01*
X0621609*
Y0266385*
X0621109Y0265885*
X0623608Y0263386D02*
X0624608D01*
X0624108*
Y0266385*
X0623608Y0265885*
X062011Y0260373D02*
X061961Y0260873D01*
X061861*
X061811Y0260373*
Y0258374*
X061861Y0257874*
X061961*
X062011Y0258374*
X0621109Y0257874D02*
X0622109D01*
X0621609*
Y0260873*
X0621109Y0260373*
X0623608D02*
X0624108Y0260873D01*
X0625108*
X0625608Y0260373*
Y0258374*
X0625108Y0257874*
X0624108*
X0623608Y0258374*
Y0260373*
X0619716Y027494D02*
X0619216Y027544D01*
X0618216*
X0617717Y027494*
Y0272941*
X0618216Y0272441*
X0619216*
X0619716Y0272941*
X0620716D02*
X0621215Y0272441D01*
X0622215*
X0622715Y0272941*
Y027494*
X0622215Y027544*
X0621215*
X0620716Y027494*
Y027444*
X0621215Y027394*
X0622715*
X0634902Y0299637D02*
X0634403Y0299137D01*
Y0298138*
X0634902Y0297638*
X0636902*
X0637402Y0298138*
Y0299137*
X0636902Y0299637*
X0634902Y0300637D02*
X0634403Y0301137D01*
Y0302136*
X0634902Y0302636*
X0635402*
X0635902Y0302136*
X0636402Y0302636*
X0636902*
X0637402Y0302136*
Y0301137*
X0636902Y0300637*
X0636402*
X0635902Y0301137*
X0635402Y0300637*
X0634902*
X0635902Y0301137D02*
Y0302136D01*
X0626241Y0299637D02*
X0625741Y0299137D01*
Y0298138*
X0626241Y0297638*
X062824*
X062874Y0298138*
Y0299137*
X062824Y0299637*
X0625741Y0300637D02*
Y0302636D01*
X0626241*
X062824Y0300637*
X062874*
X0665021Y0223161D02*
X0664521Y0222661D01*
Y0221661*
X0665021Y0221161*
X066702*
X066752Y0221661*
Y0222661*
X066702Y0223161*
X0664521Y022616D02*
X0665021Y022516D01*
X066602Y022416*
X066702*
X066752Y022466*
Y022566*
X066702Y022616*
X066652*
X066602Y022566*
Y022416*
X063254Y020318D02*
X063204Y0202681D01*
Y0201681*
X063254Y0201181*
X063454*
X0635039Y0201681*
Y0202681*
X063454Y020318*
X063204Y0206179D02*
Y020418D01*
X063354*
X063304Y020518*
Y020568*
X063354Y0206179*
X063454*
X0635039Y020568*
Y020468*
X063454Y020418*
X0650552Y0208594D02*
X0650052Y0208094D01*
Y0207094*
X0650552Y0206594*
X0652551*
X0653051Y0207094*
Y0208094*
X0652551Y0208594*
X0653051Y0211093D02*
X0650052D01*
X0651552Y0209594*
Y0211593*
X0646123Y0216665D02*
X0645623Y0216165D01*
Y0215165*
X0646123Y0214665*
X0648122*
X0648622Y0215165*
Y0216165*
X0648122Y0216665*
X0646123Y0217664D02*
X0645623Y0218164D01*
Y0219164*
X0646123Y0219664*
X0646623*
X0647122Y0219164*
Y0218664*
Y0219164*
X0647622Y0219664*
X0648122*
X0648622Y0219164*
Y0218164*
X0648122Y0217664*
X0210099Y0074834D02*
X0209599Y0074334D01*
Y0073334*
X0210099Y0072835*
X0212099*
X0212598Y0073334*
Y0074334*
X0212099Y0074834*
X0212598Y0077833D02*
Y0075834D01*
X0210599Y0077833*
X0210099*
X0209599Y0077333*
Y0076333*
X0210099Y0075834*
X0197304Y0076802D02*
X0196804Y0076303D01*
Y0075303*
X0197304Y0074803*
X0199303*
X0199803Y0075303*
Y0076303*
X0199303Y0076802*
X0199803Y0077802D02*
Y0078802D01*
Y0078302*
X0196804*
X0197304Y0077802*
M02*